G04*
G04 #@! TF.GenerationSoftware,Altium Limited,Altium Designer,23.0.1 (38)*
G04*
G04 Layer_Physical_Order=2*
G04 Layer_Color=65280*
%FSLAX25Y25*%
%MOIN*%
G70*
G04*
G04 #@! TF.SameCoordinates,C48E81DB-6E20-4E2D-80E6-7C5AFAA1A21F*
G04*
G04*
G04 #@! TF.FilePolarity,Positive*
G04*
G01*
G75*
G04:AMPARAMS|DCode=212|XSize=43.31mil|YSize=70.87mil|CornerRadius=21.65mil|HoleSize=0mil|Usage=FLASHONLY|Rotation=90.000|XOffset=0mil|YOffset=0mil|HoleType=Round|Shape=RoundedRectangle|*
%AMROUNDEDRECTD212*
21,1,0.04331,0.02756,0,0,90.0*
21,1,0.00000,0.07087,0,0,90.0*
1,1,0.04331,0.01378,0.00000*
1,1,0.04331,0.01378,0.00000*
1,1,0.04331,-0.01378,0.00000*
1,1,0.04331,-0.01378,0.00000*
%
%ADD212ROUNDEDRECTD212*%
G04:AMPARAMS|DCode=213|XSize=47.24mil|YSize=62.99mil|CornerRadius=23.62mil|HoleSize=0mil|Usage=FLASHONLY|Rotation=90.000|XOffset=0mil|YOffset=0mil|HoleType=Round|Shape=RoundedRectangle|*
%AMROUNDEDRECTD213*
21,1,0.04724,0.01575,0,0,90.0*
21,1,0.00000,0.06299,0,0,90.0*
1,1,0.04724,0.00787,0.00000*
1,1,0.04724,0.00787,0.00000*
1,1,0.04724,-0.00787,0.00000*
1,1,0.04724,-0.00787,0.00000*
%
%ADD213ROUNDEDRECTD213*%
%ADD215R,0.10827X0.10827*%
%ADD216C,0.10827*%
%ADD240C,0.06102*%
%ADD241C,0.10000*%
%ADD245C,0.08661*%
%ADD248C,0.05906*%
%ADD250C,0.01600*%
%ADD251C,0.05000*%
%ADD253C,0.01968*%
G36*
X24800Y21169D02*
X25067Y20669D01*
X24879Y20387D01*
X24739Y19685D01*
X24879Y18983D01*
X25277Y18387D01*
X25872Y17989D01*
X26575Y17850D01*
X27277Y17989D01*
X27872Y18387D01*
X28270Y18983D01*
X28410Y19685D01*
X28270Y20387D01*
X28082Y20669D01*
X28350Y21169D01*
X31591D01*
X31858Y20669D01*
X31769Y20535D01*
X31629Y19833D01*
X31769Y19131D01*
X32167Y18535D01*
X32762Y18137D01*
X33465Y17998D01*
X34167Y18137D01*
X34762Y18535D01*
X35160Y19131D01*
X35300Y19833D01*
X35160Y20535D01*
X35071Y20669D01*
X35338Y21169D01*
X38579D01*
X38847Y20669D01*
X38659Y20387D01*
X38519Y19685D01*
X38659Y18983D01*
X39057Y18387D01*
X39652Y17989D01*
X40354Y17850D01*
X41057Y17989D01*
X41652Y18387D01*
X42050Y18983D01*
X42190Y19685D01*
X42050Y20387D01*
X41862Y20669D01*
X42129Y21169D01*
X45469D01*
X45737Y20669D01*
X45548Y20387D01*
X45409Y19685D01*
X45548Y18983D01*
X45946Y18387D01*
X46542Y17989D01*
X47244Y17850D01*
X47946Y17989D01*
X48542Y18387D01*
X48940Y18983D01*
X49079Y19685D01*
X48940Y20387D01*
X48752Y20669D01*
X49019Y21169D01*
X699564Y21169D01*
X699564Y-363786D01*
X283662D01*
X283193Y-363879D01*
X282796Y-364144D01*
X282531Y-364541D01*
X282438Y-365009D01*
Y-392667D01*
X201420D01*
Y-385876D01*
X201412Y-385836D01*
X201418Y-385796D01*
X201386Y-385307D01*
X201355Y-385191D01*
X201347Y-385071D01*
X201094Y-384128D01*
X201023Y-383984D01*
X200972Y-383833D01*
X200483Y-382987D01*
X200378Y-382867D01*
X200289Y-382734D01*
X199599Y-382043D01*
X199466Y-381954D01*
X199345Y-381849D01*
X198504Y-381363D01*
X197741Y-380600D01*
X194941D01*
X193862Y-381679D01*
X193568Y-381849D01*
X193448Y-381954D01*
X193315Y-382043D01*
X192624Y-382734D01*
X192535Y-382867D01*
X192430Y-382987D01*
X192260Y-383280D01*
X191741Y-383800D01*
Y-384421D01*
X191567Y-385071D01*
X191559Y-385191D01*
X191528Y-385307D01*
X191496Y-385796D01*
X191501Y-385836D01*
X191493Y-385876D01*
Y-392667D01*
X149846D01*
Y-372195D01*
X149840Y-372165D01*
X149844Y-372134D01*
X149809Y-371430D01*
X149787Y-371342D01*
Y-371252D01*
X149641Y-370515D01*
Y-368300D01*
X145041Y-363700D01*
X137841D01*
X133341Y-368200D01*
Y-369973D01*
X133087Y-371252D01*
Y-371342D01*
X133065Y-371430D01*
X133030Y-372134D01*
X133035Y-372165D01*
X133028Y-372195D01*
Y-382888D01*
X103979D01*
Y-365009D01*
X103886Y-364541D01*
X103641Y-364174D01*
Y-364000D01*
X103405D01*
X103224Y-363879D01*
X102756Y-363786D01*
X30512D01*
X30044Y-363879D01*
X29863Y-364000D01*
X29641D01*
Y-364153D01*
X29381Y-364541D01*
X29288Y-365009D01*
Y-396266D01*
X-27320D01*
Y20639D01*
X-26790Y21169D01*
X24800D01*
D02*
G37*
%LPC*%
G36*
X593008Y17890D02*
X585102D01*
Y9984D01*
X593008D01*
Y17890D01*
D02*
G37*
G36*
X579055Y17924D02*
X578023Y17788D01*
X577062Y17390D01*
X576236Y16756D01*
X575602Y15930D01*
X575204Y14969D01*
X575068Y13937D01*
X575204Y12905D01*
X575602Y11944D01*
X576236Y11118D01*
X577062Y10484D01*
X578023Y10086D01*
X579055Y9950D01*
X580087Y10086D01*
X581048Y10484D01*
X581874Y11118D01*
X582508Y11944D01*
X582906Y12905D01*
X583042Y13937D01*
X582906Y14969D01*
X582508Y15930D01*
X581874Y16756D01*
X581048Y17390D01*
X580087Y17788D01*
X579055Y17924D01*
D02*
G37*
G36*
X569055D02*
X568023Y17788D01*
X567062Y17390D01*
X566236Y16756D01*
X565602Y15930D01*
X565204Y14969D01*
X565068Y13937D01*
X565204Y12905D01*
X565602Y11944D01*
X566236Y11118D01*
X567062Y10484D01*
X568023Y10086D01*
X569055Y9950D01*
X570087Y10086D01*
X571048Y10484D01*
X571874Y11118D01*
X572508Y11944D01*
X572906Y12905D01*
X573042Y13937D01*
X572906Y14969D01*
X572508Y15930D01*
X571874Y16756D01*
X571048Y17390D01*
X570087Y17788D01*
X569055Y17924D01*
D02*
G37*
G36*
X559055D02*
X558023Y17788D01*
X557062Y17390D01*
X556236Y16756D01*
X555602Y15930D01*
X555204Y14969D01*
X555068Y13937D01*
X555204Y12905D01*
X555602Y11944D01*
X556236Y11118D01*
X557062Y10484D01*
X558023Y10086D01*
X559055Y9950D01*
X560087Y10086D01*
X561049Y10484D01*
X561874Y11118D01*
X562508Y11944D01*
X562906Y12905D01*
X563042Y13937D01*
X562906Y14969D01*
X562508Y15930D01*
X561874Y16756D01*
X561049Y17390D01*
X560087Y17788D01*
X559055Y17924D01*
D02*
G37*
G36*
X539055D02*
X538023Y17788D01*
X537062Y17390D01*
X536236Y16756D01*
X535602Y15930D01*
X535204Y14969D01*
X535068Y13937D01*
X535204Y12905D01*
X535602Y11944D01*
X536236Y11118D01*
X537062Y10484D01*
X538023Y10086D01*
X539055Y9950D01*
X540087Y10086D01*
X541048Y10484D01*
X541874Y11118D01*
X542508Y11944D01*
X542906Y12905D01*
X543042Y13937D01*
X542906Y14969D01*
X542508Y15930D01*
X541874Y16756D01*
X541048Y17390D01*
X540087Y17788D01*
X539055Y17924D01*
D02*
G37*
G36*
X589055Y7924D02*
X588023Y7788D01*
X587062Y7390D01*
X586236Y6756D01*
X585602Y5930D01*
X585204Y4969D01*
X585068Y3937D01*
X585204Y2905D01*
X585602Y1944D01*
X586236Y1118D01*
X587062Y484D01*
X588023Y86D01*
X589055Y-50D01*
X590087Y86D01*
X591048Y484D01*
X591874Y1118D01*
X592508Y1944D01*
X592906Y2905D01*
X593042Y3937D01*
X592906Y4969D01*
X592508Y5930D01*
X591874Y6756D01*
X591048Y7390D01*
X590087Y7788D01*
X589055Y7924D01*
D02*
G37*
G36*
X579055D02*
X578023Y7788D01*
X577062Y7390D01*
X576236Y6756D01*
X575602Y5930D01*
X575204Y4969D01*
X575068Y3937D01*
X575204Y2905D01*
X575602Y1944D01*
X576236Y1118D01*
X577062Y484D01*
X578023Y86D01*
X579055Y-50D01*
X580087Y86D01*
X581048Y484D01*
X581874Y1118D01*
X582508Y1944D01*
X582906Y2905D01*
X583042Y3937D01*
X582906Y4969D01*
X582508Y5930D01*
X581874Y6756D01*
X581048Y7390D01*
X580087Y7788D01*
X579055Y7924D01*
D02*
G37*
G36*
X569055D02*
X568023Y7788D01*
X567062Y7390D01*
X566236Y6756D01*
X565602Y5930D01*
X565204Y4969D01*
X565068Y3937D01*
X565204Y2905D01*
X565602Y1944D01*
X566236Y1118D01*
X567062Y484D01*
X568023Y86D01*
X569055Y-50D01*
X570087Y86D01*
X571048Y484D01*
X571874Y1118D01*
X572508Y1944D01*
X572906Y2905D01*
X573042Y3937D01*
X572906Y4969D01*
X572508Y5930D01*
X571874Y6756D01*
X571048Y7390D01*
X570087Y7788D01*
X569055Y7924D01*
D02*
G37*
G36*
X559055D02*
X558023Y7788D01*
X557062Y7390D01*
X556236Y6756D01*
X555602Y5930D01*
X555204Y4969D01*
X555068Y3937D01*
X555204Y2905D01*
X555602Y1944D01*
X556236Y1118D01*
X557062Y484D01*
X558023Y86D01*
X559055Y-50D01*
X560087Y86D01*
X561049Y484D01*
X561874Y1118D01*
X562508Y1944D01*
X562906Y2905D01*
X563042Y3937D01*
X562906Y4969D01*
X562508Y5930D01*
X561874Y6756D01*
X561049Y7390D01*
X560087Y7788D01*
X559055Y7924D01*
D02*
G37*
G36*
X539055D02*
X538023Y7788D01*
X537062Y7390D01*
X536236Y6756D01*
X535602Y5930D01*
X535204Y4969D01*
X535068Y3937D01*
X535204Y2905D01*
X535602Y1944D01*
X536236Y1118D01*
X537062Y484D01*
X538023Y86D01*
X539055Y-50D01*
X540087Y86D01*
X541048Y484D01*
X541874Y1118D01*
X542508Y1944D01*
X542906Y2905D01*
X543042Y3937D01*
X542906Y4969D01*
X542508Y5930D01*
X541874Y6756D01*
X541048Y7390D01*
X540087Y7788D01*
X539055Y7924D01*
D02*
G37*
G36*
X310069Y18446D02*
X308343Y18310D01*
X306659Y17906D01*
X305060Y17243D01*
X303583Y16339D01*
X302267Y15214D01*
X301142Y13897D01*
X300238Y12421D01*
X299575Y10821D01*
X299171Y9138D01*
X299035Y7412D01*
X299171Y5686D01*
X299575Y4002D01*
X300238Y2402D01*
X301142Y926D01*
X302267Y-390D01*
X303583Y-1515D01*
X305060Y-2420D01*
X306659Y-3082D01*
X308343Y-3486D01*
X310069Y-3622D01*
X311795Y-3486D01*
X313479Y-3082D01*
X315078Y-2420D01*
X316555Y-1515D01*
X317871Y-390D01*
X318996Y926D01*
X319900Y2402D01*
X320563Y4002D01*
X320967Y5686D01*
X321103Y7412D01*
X320967Y9138D01*
X320563Y10821D01*
X319900Y12421D01*
X318996Y13897D01*
X317871Y15214D01*
X316555Y16339D01*
X315078Y17243D01*
X313479Y17906D01*
X311795Y18310D01*
X310069Y18446D01*
D02*
G37*
G36*
X71880D02*
X70154Y18310D01*
X68470Y17906D01*
X66871Y17243D01*
X65394Y16339D01*
X64078Y15214D01*
X62953Y13897D01*
X62049Y12421D01*
X61386Y10821D01*
X60982Y9138D01*
X60846Y7412D01*
X60982Y5686D01*
X61386Y4002D01*
X62049Y2402D01*
X62953Y926D01*
X64078Y-390D01*
X65394Y-1515D01*
X66871Y-2420D01*
X68470Y-3082D01*
X70154Y-3486D01*
X71880Y-3622D01*
X73606Y-3486D01*
X75290Y-3082D01*
X76889Y-2420D01*
X78366Y-1515D01*
X79682Y-390D01*
X80807Y926D01*
X81711Y2402D01*
X82374Y4002D01*
X82778Y5686D01*
X82914Y7412D01*
X82778Y9138D01*
X82374Y10821D01*
X81711Y12421D01*
X80807Y13897D01*
X79682Y15214D01*
X78366Y16339D01*
X76889Y17243D01*
X75290Y17906D01*
X73606Y18310D01*
X71880Y18446D01*
D02*
G37*
G36*
X651545Y18288D02*
X649819Y18153D01*
X648136Y17748D01*
X646536Y17086D01*
X645060Y16181D01*
X643743Y15057D01*
X642619Y13740D01*
X641714Y12264D01*
X641051Y10664D01*
X640647Y8980D01*
X640511Y7254D01*
X640647Y5528D01*
X641051Y3845D01*
X641714Y2245D01*
X642619Y769D01*
X643743Y-548D01*
X645060Y-1672D01*
X646536Y-2577D01*
X648136Y-3240D01*
X649819Y-3644D01*
X651545Y-3780D01*
X653271Y-3644D01*
X654955Y-3240D01*
X656555Y-2577D01*
X658031Y-1672D01*
X659347Y-548D01*
X660472Y769D01*
X661377Y2245D01*
X662039Y3845D01*
X662443Y5528D01*
X662579Y7254D01*
X662443Y8980D01*
X662039Y10664D01*
X661377Y12264D01*
X660472Y13740D01*
X659347Y15057D01*
X658031Y16181D01*
X656555Y17086D01*
X654955Y17748D01*
X653271Y18153D01*
X651545Y18288D01*
D02*
G37*
G36*
X413356D02*
X411630Y18153D01*
X409947Y17748D01*
X408347Y17086D01*
X406871Y16181D01*
X405554Y15057D01*
X404430Y13740D01*
X403525Y12264D01*
X402862Y10664D01*
X402458Y8980D01*
X402322Y7254D01*
X402458Y5528D01*
X402862Y3845D01*
X403525Y2245D01*
X404430Y769D01*
X405554Y-548D01*
X406871Y-1672D01*
X408347Y-2577D01*
X409947Y-3240D01*
X411630Y-3644D01*
X413356Y-3780D01*
X415082Y-3644D01*
X416766Y-3240D01*
X418366Y-2577D01*
X419842Y-1672D01*
X421159Y-548D01*
X422283Y769D01*
X423188Y2245D01*
X423850Y3845D01*
X424254Y5528D01*
X424390Y7254D01*
X424254Y8980D01*
X423850Y10664D01*
X423188Y12264D01*
X422283Y13740D01*
X421159Y15057D01*
X419842Y16181D01*
X418366Y17086D01*
X416766Y17748D01*
X415082Y18153D01*
X413356Y18288D01*
D02*
G37*
G36*
X615158Y-7023D02*
X614455Y-7163D01*
X613860Y-7561D01*
X613462Y-8156D01*
X613322Y-8858D01*
X613462Y-9561D01*
X613860Y-10156D01*
X614455Y-10554D01*
X615158Y-10694D01*
X615860Y-10554D01*
X616455Y-10156D01*
X616853Y-9561D01*
X616993Y-8858D01*
X616853Y-8156D01*
X616455Y-7561D01*
X615860Y-7163D01*
X615158Y-7023D01*
D02*
G37*
G36*
X47244D02*
X46542Y-7163D01*
X45946Y-7561D01*
X45548Y-8156D01*
X45409Y-8858D01*
X45548Y-9561D01*
X45946Y-10156D01*
X46542Y-10554D01*
X47244Y-10694D01*
X47946Y-10554D01*
X48542Y-10156D01*
X48940Y-9561D01*
X49079Y-8858D01*
X48940Y-8156D01*
X48542Y-7561D01*
X47946Y-7163D01*
X47244Y-7023D01*
D02*
G37*
G36*
X40354D02*
X39652Y-7163D01*
X39057Y-7561D01*
X38659Y-8156D01*
X38519Y-8858D01*
X38659Y-9561D01*
X39057Y-10156D01*
X39652Y-10554D01*
X40354Y-10694D01*
X41057Y-10554D01*
X41652Y-10156D01*
X42050Y-9561D01*
X42190Y-8858D01*
X42050Y-8156D01*
X41652Y-7561D01*
X41057Y-7163D01*
X40354Y-7023D01*
D02*
G37*
G36*
X33465D02*
X32762Y-7163D01*
X32167Y-7561D01*
X31769Y-8156D01*
X31629Y-8858D01*
X31769Y-9561D01*
X32167Y-10156D01*
X32762Y-10554D01*
X33465Y-10694D01*
X34167Y-10554D01*
X34762Y-10156D01*
X35160Y-9561D01*
X35300Y-8858D01*
X35160Y-8156D01*
X34762Y-7561D01*
X34167Y-7163D01*
X33465Y-7023D01*
D02*
G37*
G36*
X26495Y-7156D02*
X25793Y-7296D01*
X25198Y-7694D01*
X24800Y-8289D01*
X24660Y-8991D01*
X24800Y-9694D01*
X25198Y-10289D01*
X25793Y-10687D01*
X26495Y-10827D01*
X27198Y-10687D01*
X27793Y-10289D01*
X28191Y-9694D01*
X28330Y-8991D01*
X28191Y-8289D01*
X27793Y-7694D01*
X27198Y-7296D01*
X26495Y-7156D01*
D02*
G37*
G36*
X685039Y13542D02*
X682921Y13375D01*
X680855Y12879D01*
X678892Y12066D01*
X677080Y10955D01*
X675464Y9576D01*
X674084Y7960D01*
X672974Y6148D01*
X672160Y4185D01*
X671664Y2118D01*
X671498Y0D01*
X671664Y-2118D01*
X672160Y-4185D01*
X672974Y-6148D01*
X674084Y-7960D01*
X675464Y-9576D01*
X677080Y-10955D01*
X678892Y-12066D01*
X680855Y-12879D01*
X682921Y-13375D01*
X685039Y-13542D01*
X687158Y-13375D01*
X689224Y-12879D01*
X691187Y-12066D01*
X692999Y-10955D01*
X694615Y-9576D01*
X695995Y-7960D01*
X697105Y-6148D01*
X697918Y-4185D01*
X698414Y-2118D01*
X698581Y0D01*
X698414Y2118D01*
X697918Y4185D01*
X697105Y6148D01*
X695995Y7960D01*
X694615Y9576D01*
X692999Y10955D01*
X691187Y12066D01*
X689224Y12879D01*
X687158Y13375D01*
X685039Y13542D01*
D02*
G37*
G36*
X0D02*
X-2118Y13375D01*
X-4185Y12879D01*
X-6148Y12066D01*
X-7960Y10955D01*
X-9576Y9576D01*
X-10955Y7960D01*
X-12066Y6148D01*
X-12879Y4185D01*
X-13375Y2118D01*
X-13542Y0D01*
X-13375Y-2118D01*
X-12879Y-4185D01*
X-12066Y-6148D01*
X-10955Y-7960D01*
X-9576Y-9576D01*
X-7960Y-10955D01*
X-6148Y-12066D01*
X-4185Y-12879D01*
X-2118Y-13375D01*
X0Y-13542D01*
X2118Y-13375D01*
X4185Y-12879D01*
X6148Y-12066D01*
X7960Y-10955D01*
X9576Y-9576D01*
X10955Y-7960D01*
X12066Y-6148D01*
X12879Y-4185D01*
X13375Y-2118D01*
X13542Y0D01*
X13375Y2118D01*
X12879Y4185D01*
X12066Y6148D01*
X10955Y7960D01*
X9576Y9576D01*
X7960Y10955D01*
X6148Y12066D01*
X4185Y12879D01*
X2118Y13375D01*
X0Y13542D01*
D02*
G37*
G36*
X660236Y-13125D02*
X659534Y-13265D01*
X658939Y-13663D01*
X658541Y-14258D01*
X658401Y-14961D01*
X658541Y-15663D01*
X658939Y-16258D01*
X659534Y-16656D01*
X660236Y-16796D01*
X660939Y-16656D01*
X661534Y-16258D01*
X661932Y-15663D01*
X662072Y-14961D01*
X661932Y-14258D01*
X661534Y-13663D01*
X660939Y-13265D01*
X660236Y-13125D01*
D02*
G37*
G36*
X640640Y-15417D02*
X639666Y-15611D01*
X638840Y-16163D01*
X638288Y-16988D01*
X638095Y-17962D01*
X638288Y-18936D01*
X638840Y-19762D01*
X639666Y-20313D01*
X640640Y-20507D01*
X641614Y-20313D01*
X642439Y-19762D01*
X642991Y-18936D01*
X643185Y-17962D01*
X642991Y-16988D01*
X642439Y-16163D01*
X641614Y-15611D01*
X640640Y-15417D01*
D02*
G37*
G36*
X658465Y-20064D02*
X657762Y-20204D01*
X657167Y-20602D01*
X656769Y-21197D01*
X656629Y-21899D01*
X656769Y-22602D01*
X657167Y-23197D01*
X657762Y-23595D01*
X658465Y-23734D01*
X659167Y-23595D01*
X659762Y-23197D01*
X660160Y-22602D01*
X660300Y-21899D01*
X660160Y-21197D01*
X659762Y-20602D01*
X659167Y-20204D01*
X658465Y-20064D01*
D02*
G37*
G36*
X625000D02*
X624298Y-20204D01*
X623702Y-20602D01*
X623304Y-21197D01*
X623165Y-21899D01*
X623304Y-22602D01*
X623702Y-23197D01*
X624298Y-23595D01*
X625000Y-23734D01*
X625702Y-23595D01*
X626298Y-23197D01*
X626696Y-22602D01*
X626835Y-21899D01*
X626696Y-21197D01*
X626298Y-20602D01*
X625702Y-20204D01*
X625000Y-20064D01*
D02*
G37*
G36*
X82785Y-19945D02*
X81811Y-20139D01*
X80986Y-20690D01*
X80434Y-21516D01*
X80240Y-22490D01*
X80434Y-23464D01*
X80986Y-24289D01*
X81811Y-24841D01*
X82785Y-25035D01*
X83759Y-24841D01*
X84585Y-24289D01*
X85137Y-23464D01*
X85330Y-22490D01*
X85137Y-21516D01*
X84585Y-20690D01*
X83759Y-20139D01*
X82785Y-19945D01*
D02*
G37*
G36*
X658465Y-27938D02*
X657762Y-28078D01*
X657167Y-28475D01*
X656769Y-29071D01*
X656629Y-29773D01*
X656769Y-30476D01*
X657167Y-31071D01*
X657762Y-31469D01*
X658465Y-31609D01*
X659167Y-31469D01*
X659762Y-31071D01*
X660160Y-30476D01*
X660300Y-29773D01*
X660160Y-29071D01*
X659762Y-28475D01*
X659167Y-28078D01*
X658465Y-27938D01*
D02*
G37*
G36*
X625000D02*
X624298Y-28078D01*
X623702Y-28475D01*
X623304Y-29071D01*
X623165Y-29773D01*
X623304Y-30476D01*
X623702Y-31071D01*
X624298Y-31469D01*
X625000Y-31609D01*
X625702Y-31469D01*
X626298Y-31071D01*
X626696Y-30476D01*
X626835Y-29773D01*
X626696Y-29071D01*
X626298Y-28475D01*
X625702Y-28078D01*
X625000Y-27938D01*
D02*
G37*
G36*
X640640Y-31165D02*
X639666Y-31359D01*
X638840Y-31911D01*
X638288Y-32736D01*
X638095Y-33710D01*
X638288Y-34684D01*
X638840Y-35510D01*
X639666Y-36061D01*
X640640Y-36255D01*
X641614Y-36061D01*
X642439Y-35510D01*
X642991Y-34684D01*
X643185Y-33710D01*
X642991Y-32736D01*
X642439Y-31911D01*
X641614Y-31359D01*
X640640Y-31165D01*
D02*
G37*
G36*
X679517Y-35188D02*
X678815Y-35327D01*
X678220Y-35725D01*
X677822Y-36321D01*
X677682Y-37023D01*
X677822Y-37725D01*
X678220Y-38321D01*
X678815Y-38718D01*
X679517Y-38858D01*
X680220Y-38718D01*
X680815Y-38321D01*
X681213Y-37725D01*
X681353Y-37023D01*
X681213Y-36321D01*
X680815Y-35725D01*
X680220Y-35327D01*
X679517Y-35188D01*
D02*
G37*
G36*
X658465Y-35812D02*
X657762Y-35952D01*
X657167Y-36349D01*
X656769Y-36945D01*
X656629Y-37647D01*
X656769Y-38350D01*
X657167Y-38945D01*
X657762Y-39343D01*
X658465Y-39483D01*
X659167Y-39343D01*
X659762Y-38945D01*
X660160Y-38350D01*
X660300Y-37647D01*
X660160Y-36945D01*
X659762Y-36349D01*
X659167Y-35952D01*
X658465Y-35812D01*
D02*
G37*
G36*
X101575Y-40291D02*
X100873Y-40430D01*
X100277Y-40828D01*
X99879Y-41424D01*
X99739Y-42126D01*
X99879Y-42828D01*
X100277Y-43424D01*
X100873Y-43821D01*
X101575Y-43961D01*
X102277Y-43821D01*
X102873Y-43424D01*
X103270Y-42828D01*
X103410Y-42126D01*
X103270Y-41424D01*
X102873Y-40828D01*
X102277Y-40430D01*
X101575Y-40291D01*
D02*
G37*
G36*
X675591Y-40684D02*
X674888Y-40824D01*
X674293Y-41222D01*
X673895Y-41817D01*
X673755Y-42520D01*
X673895Y-43222D01*
X674293Y-43817D01*
X674888Y-44215D01*
X675591Y-44355D01*
X676293Y-44215D01*
X676888Y-43817D01*
X677286Y-43222D01*
X677426Y-42520D01*
X677286Y-41817D01*
X676888Y-41222D01*
X676293Y-40824D01*
X675591Y-40684D01*
D02*
G37*
G36*
X64173D02*
X63471Y-40824D01*
X62875Y-41222D01*
X62478Y-41817D01*
X62338Y-42520D01*
X62478Y-43222D01*
X62875Y-43817D01*
X63471Y-44215D01*
X64173Y-44355D01*
X64876Y-44215D01*
X65471Y-43817D01*
X65869Y-43222D01*
X66009Y-42520D01*
X65869Y-41817D01*
X65471Y-41222D01*
X64876Y-40824D01*
X64173Y-40684D01*
D02*
G37*
G36*
X686319Y-41718D02*
X685617Y-41858D01*
X685021Y-42255D01*
X684623Y-42851D01*
X684484Y-43553D01*
X684623Y-44256D01*
X685021Y-44851D01*
X685617Y-45249D01*
X686319Y-45388D01*
X687021Y-45249D01*
X687617Y-44851D01*
X688015Y-44256D01*
X688154Y-43553D01*
X688015Y-42851D01*
X687617Y-42255D01*
X687021Y-41858D01*
X686319Y-41718D01*
D02*
G37*
G36*
X614567Y-43047D02*
X613865Y-43186D01*
X613269Y-43584D01*
X612871Y-44180D01*
X612732Y-44882D01*
X612871Y-45584D01*
X613269Y-46180D01*
X613865Y-46577D01*
X614567Y-46717D01*
X615269Y-46577D01*
X615865Y-46180D01*
X616262Y-45584D01*
X616402Y-44882D01*
X616262Y-44180D01*
X615865Y-43584D01*
X615269Y-43186D01*
X614567Y-43047D01*
D02*
G37*
G36*
X625000Y-46245D02*
X624298Y-46385D01*
X623702Y-46783D01*
X623304Y-47378D01*
X623165Y-48080D01*
X623304Y-48783D01*
X623702Y-49378D01*
X624298Y-49776D01*
X625000Y-49916D01*
X625702Y-49776D01*
X626298Y-49378D01*
X626696Y-48783D01*
X626835Y-48080D01*
X626696Y-47378D01*
X626298Y-46783D01*
X625702Y-46385D01*
X625000Y-46245D01*
D02*
G37*
G36*
X659449Y-47377D02*
X658746Y-47517D01*
X658151Y-47915D01*
X657753Y-48510D01*
X657614Y-49213D01*
X657753Y-49915D01*
X658151Y-50510D01*
X658746Y-50908D01*
X659449Y-51048D01*
X660151Y-50908D01*
X660746Y-50510D01*
X661144Y-49915D01*
X661284Y-49213D01*
X661144Y-48510D01*
X660746Y-47915D01*
X660151Y-47517D01*
X659449Y-47377D01*
D02*
G37*
G36*
X65945Y-48214D02*
X65243Y-48353D01*
X64647Y-48751D01*
X64249Y-49347D01*
X64110Y-50049D01*
X64249Y-50751D01*
X64647Y-51347D01*
X65243Y-51744D01*
X65945Y-51884D01*
X66647Y-51744D01*
X67243Y-51347D01*
X67641Y-50751D01*
X67780Y-50049D01*
X67641Y-49347D01*
X67243Y-48751D01*
X66647Y-48353D01*
X65945Y-48214D01*
D02*
G37*
G36*
X696577Y-49617D02*
X695875Y-49757D01*
X695280Y-50155D01*
X694882Y-50750D01*
X694742Y-51453D01*
X694882Y-52155D01*
X695280Y-52750D01*
X695875Y-53148D01*
X696577Y-53288D01*
X697280Y-53148D01*
X697875Y-52750D01*
X698273Y-52155D01*
X698413Y-51453D01*
X698273Y-50750D01*
X697875Y-50155D01*
X697280Y-49757D01*
X696577Y-49617D01*
D02*
G37*
G36*
X676772Y-49740D02*
X676069Y-49879D01*
X675474Y-50277D01*
X675076Y-50872D01*
X674936Y-51575D01*
X675076Y-52277D01*
X675474Y-52873D01*
Y-53033D01*
X675076Y-53628D01*
X674936Y-54331D01*
X675076Y-55033D01*
X675474Y-55628D01*
X676069Y-56026D01*
X676772Y-56166D01*
X677474Y-56026D01*
X678069Y-55628D01*
X678467Y-55033D01*
X678607Y-54331D01*
X678467Y-53628D01*
X678069Y-53033D01*
Y-52873D01*
X678467Y-52277D01*
X678607Y-51575D01*
X678467Y-50872D01*
X678069Y-50277D01*
X677474Y-49879D01*
X676772Y-49740D01*
D02*
G37*
G36*
X82785Y-51441D02*
X81811Y-51635D01*
X80986Y-52186D01*
X80434Y-53012D01*
X80240Y-53986D01*
X80434Y-54960D01*
X80986Y-55785D01*
X81811Y-56337D01*
X82785Y-56531D01*
X83759Y-56337D01*
X84585Y-55785D01*
X85137Y-54960D01*
X85330Y-53986D01*
X85137Y-53012D01*
X84585Y-52186D01*
X83759Y-51635D01*
X82785Y-51441D01*
D02*
G37*
G36*
X623228Y-53283D02*
X622526Y-53423D01*
X621931Y-53820D01*
X621533Y-54416D01*
X621393Y-55118D01*
X621533Y-55820D01*
X621931Y-56416D01*
X622526Y-56814D01*
X623228Y-56953D01*
X623931Y-56814D01*
X624526Y-56416D01*
X624924Y-55820D01*
X625064Y-55118D01*
X624924Y-54416D01*
X624526Y-53820D01*
X623931Y-53423D01*
X623228Y-53283D01*
D02*
G37*
G36*
X658114Y-54879D02*
X657412Y-55019D01*
X656816Y-55417D01*
X656419Y-56012D01*
X656279Y-56714D01*
X656419Y-57417D01*
X656816Y-58012D01*
X657412Y-58410D01*
X658114Y-58550D01*
X658816Y-58410D01*
X659412Y-58012D01*
X659810Y-57417D01*
X659949Y-56714D01*
X659810Y-56012D01*
X659412Y-55417D01*
X658816Y-55019D01*
X658114Y-54879D01*
D02*
G37*
G36*
X99410Y-56088D02*
X98707Y-56227D01*
X98112Y-56625D01*
X97714Y-57221D01*
X97574Y-57923D01*
X97714Y-58625D01*
X98112Y-59221D01*
X98707Y-59618D01*
X99410Y-59758D01*
X100112Y-59618D01*
X100707Y-59221D01*
X101105Y-58625D01*
X101245Y-57923D01*
X101105Y-57221D01*
X100707Y-56625D01*
X100112Y-56227D01*
X99410Y-56088D01*
D02*
G37*
G36*
X65945D02*
X65243Y-56227D01*
X64647Y-56625D01*
X64249Y-57221D01*
X64110Y-57923D01*
X64249Y-58625D01*
X64647Y-59221D01*
X65243Y-59618D01*
X65945Y-59758D01*
X66647Y-59618D01*
X67243Y-59221D01*
X67641Y-58625D01*
X67780Y-57923D01*
X67641Y-57221D01*
X67243Y-56625D01*
X66647Y-56227D01*
X65945Y-56088D01*
D02*
G37*
G36*
X623511Y-60717D02*
X622808Y-60857D01*
X622213Y-61255D01*
X621815Y-61850D01*
X621675Y-62552D01*
X621815Y-63255D01*
X622213Y-63850D01*
X622808Y-64248D01*
X623511Y-64388D01*
X624213Y-64248D01*
X624808Y-63850D01*
X625206Y-63255D01*
X625346Y-62552D01*
X625206Y-61850D01*
X624808Y-61255D01*
X624213Y-60857D01*
X623511Y-60717D01*
D02*
G37*
G36*
X657445Y-61690D02*
X656743Y-61830D01*
X656147Y-62228D01*
X655750Y-62823D01*
X655610Y-63525D01*
X655750Y-64228D01*
X656147Y-64823D01*
X656743Y-65221D01*
X657445Y-65361D01*
X658147Y-65221D01*
X658743Y-64823D01*
X659141Y-64228D01*
X659280Y-63525D01*
X659141Y-62823D01*
X658743Y-62228D01*
X658147Y-61830D01*
X657445Y-61690D01*
D02*
G37*
G36*
X99410Y-63962D02*
X98707Y-64101D01*
X98112Y-64499D01*
X97714Y-65095D01*
X97574Y-65797D01*
X97714Y-66499D01*
X98112Y-67095D01*
X98707Y-67492D01*
X99410Y-67632D01*
X100112Y-67492D01*
X100707Y-67095D01*
X101105Y-66499D01*
X101245Y-65797D01*
X101105Y-65095D01*
X100707Y-64499D01*
X100112Y-64101D01*
X99410Y-63962D01*
D02*
G37*
G36*
X65945D02*
X65243Y-64101D01*
X64647Y-64499D01*
X64249Y-65095D01*
X64110Y-65797D01*
X64249Y-66499D01*
X64647Y-67095D01*
X65243Y-67492D01*
X65945Y-67632D01*
X66647Y-67492D01*
X67243Y-67095D01*
X67641Y-66499D01*
X67780Y-65797D01*
X67641Y-65095D01*
X67243Y-64499D01*
X66647Y-64101D01*
X65945Y-63962D01*
D02*
G37*
G36*
X640640Y-62661D02*
X639666Y-62855D01*
X638840Y-63407D01*
X638288Y-64232D01*
X638095Y-65206D01*
X638288Y-66180D01*
X638840Y-67006D01*
X639666Y-67558D01*
X640640Y-67751D01*
X641614Y-67558D01*
X642439Y-67006D01*
X642991Y-66180D01*
X643185Y-65206D01*
X642991Y-64232D01*
X642439Y-63407D01*
X641614Y-62855D01*
X640640Y-62661D01*
D02*
G37*
G36*
X689466Y-64330D02*
X688764Y-64470D01*
X688168Y-64868D01*
X687771Y-65463D01*
X687631Y-66165D01*
X687771Y-66868D01*
X688168Y-67463D01*
X688764Y-67861D01*
X689466Y-68001D01*
X690168Y-67861D01*
X690764Y-67463D01*
X691162Y-66868D01*
X691301Y-66165D01*
X691162Y-65463D01*
X690764Y-64868D01*
X690168Y-64470D01*
X689466Y-64330D01*
D02*
G37*
G36*
X680082Y-62348D02*
X679380Y-62488D01*
X678784Y-62886D01*
X678386Y-63481D01*
X678247Y-64183D01*
X678386Y-64886D01*
X678784Y-65481D01*
X679380Y-65879D01*
X680082Y-66019D01*
X680784Y-65879D01*
X680857Y-65830D01*
X681307Y-66131D01*
X681292Y-66209D01*
X681431Y-66911D01*
X681829Y-67507D01*
X682425Y-67905D01*
X683127Y-68044D01*
X683829Y-67905D01*
X684425Y-67507D01*
X684823Y-66911D01*
X684962Y-66209D01*
X684823Y-65507D01*
X684425Y-64911D01*
X683829Y-64513D01*
X683127Y-64374D01*
X682425Y-64513D01*
X682352Y-64562D01*
X681902Y-64262D01*
X681917Y-64183D01*
X681777Y-63481D01*
X681380Y-62886D01*
X680784Y-62488D01*
X680082Y-62348D01*
D02*
G37*
G36*
X574016Y-68637D02*
X573313Y-68777D01*
X572718Y-69175D01*
X572691Y-69215D01*
X572191D01*
X572164Y-69175D01*
X571568Y-68777D01*
X570866Y-68637D01*
X570164Y-68777D01*
X569568Y-69175D01*
X569171Y-69770D01*
X569031Y-70472D01*
X569171Y-71175D01*
X569359Y-71457D01*
X569171Y-71739D01*
X569031Y-72441D01*
X569171Y-73143D01*
X569359Y-73425D01*
X569171Y-73707D01*
X569031Y-74410D01*
X569171Y-75112D01*
X569568Y-75707D01*
X570164Y-76105D01*
X570866Y-76245D01*
X571568Y-76105D01*
X572164Y-75707D01*
X572191Y-75667D01*
X572691D01*
X572718Y-75707D01*
X573313Y-76105D01*
X574016Y-76245D01*
X574718Y-76105D01*
X575314Y-75707D01*
X575711Y-75112D01*
X575851Y-74410D01*
X575711Y-73707D01*
X575523Y-73425D01*
X575711Y-73143D01*
X575851Y-72441D01*
X575711Y-71739D01*
X575523Y-71457D01*
X575711Y-71175D01*
X575851Y-70472D01*
X575711Y-69770D01*
X575314Y-69175D01*
X574718Y-68777D01*
X574016Y-68637D01*
D02*
G37*
G36*
X82785Y-67189D02*
X81811Y-67383D01*
X80986Y-67934D01*
X80434Y-68760D01*
X80240Y-69734D01*
X80434Y-70708D01*
X80986Y-71533D01*
X81811Y-72085D01*
X82785Y-72279D01*
X83759Y-72085D01*
X84585Y-71533D01*
X85137Y-70708D01*
X85330Y-69734D01*
X85137Y-68760D01*
X84585Y-67934D01*
X83759Y-67383D01*
X82785Y-67189D01*
D02*
G37*
G36*
X-23622Y-58204D02*
X-24324Y-58344D01*
X-24920Y-58742D01*
X-25318Y-59337D01*
X-25457Y-60039D01*
X-25318Y-60742D01*
X-25032Y-61168D01*
X-24958Y-61516D01*
X-25032Y-61863D01*
X-25318Y-62290D01*
X-25457Y-62992D01*
X-25318Y-63694D01*
X-24920Y-64290D01*
X-24324Y-64688D01*
X-24234Y-64706D01*
Y-65215D01*
X-24324Y-65234D01*
X-24920Y-65631D01*
X-25318Y-66227D01*
X-25457Y-66929D01*
X-25318Y-67631D01*
X-24920Y-68227D01*
X-24324Y-68625D01*
X-24234Y-68643D01*
Y-69152D01*
X-24324Y-69171D01*
X-24920Y-69568D01*
X-25318Y-70164D01*
X-25457Y-70866D01*
X-25318Y-71569D01*
X-24920Y-72164D01*
X-24324Y-72562D01*
X-23622Y-72701D01*
X-22920Y-72562D01*
X-22324Y-72164D01*
X-21926Y-71569D01*
X-21787Y-70866D01*
X-21926Y-70164D01*
X-22324Y-69568D01*
X-22920Y-69171D01*
X-23010Y-69152D01*
Y-68643D01*
X-22920Y-68625D01*
X-22324Y-68227D01*
X-21926Y-67631D01*
X-21787Y-66929D01*
X-21926Y-66227D01*
X-22324Y-65631D01*
X-22920Y-65234D01*
X-23010Y-65215D01*
Y-64706D01*
X-22920Y-64688D01*
X-22324Y-64290D01*
X-21926Y-63694D01*
X-21787Y-62992D01*
X-21926Y-62290D01*
X-22212Y-61863D01*
X-22286Y-61516D01*
X-22212Y-61168D01*
X-21926Y-60742D01*
X-21787Y-60039D01*
X-21926Y-59337D01*
X-22324Y-58742D01*
X-22920Y-58344D01*
X-23622Y-58204D01*
D02*
G37*
G36*
X670538Y-72574D02*
X669836Y-72714D01*
X669488Y-72946D01*
X669140Y-72714D01*
X668438Y-72574D01*
X667736Y-72714D01*
X667140Y-73112D01*
X666743Y-73707D01*
X666603Y-74409D01*
X666743Y-75112D01*
X667140Y-75707D01*
X667736Y-76105D01*
X668438Y-76245D01*
X669140Y-76105D01*
X669488Y-75873D01*
X669836Y-76105D01*
X670538Y-76245D01*
X671241Y-76105D01*
X671836Y-75707D01*
X672234Y-75112D01*
X672373Y-74409D01*
X672234Y-73707D01*
X671836Y-73112D01*
X671241Y-72714D01*
X670538Y-72574D01*
D02*
G37*
G36*
X658053Y-69353D02*
X657351Y-69493D01*
X656756Y-69890D01*
X656358Y-70486D01*
X656218Y-71188D01*
X656358Y-71890D01*
X656756Y-72486D01*
X657351Y-72884D01*
X658053Y-73023D01*
X658756Y-72884D01*
X659351Y-72486D01*
X659749Y-71890D01*
X659889Y-71188D01*
X659749Y-70486D01*
X659351Y-69890D01*
X658756Y-69493D01*
X658053Y-69353D01*
D02*
G37*
G36*
X131890Y-70851D02*
X131187Y-70991D01*
X130592Y-71389D01*
X130194Y-71984D01*
X130054Y-72687D01*
X130194Y-73389D01*
X130592Y-73984D01*
X131187Y-74382D01*
X131890Y-74522D01*
X132592Y-74382D01*
X133187Y-73984D01*
X133585Y-73389D01*
X133725Y-72687D01*
X133585Y-71984D01*
X133187Y-71389D01*
X132592Y-70991D01*
X131890Y-70851D01*
D02*
G37*
G36*
X597227Y-75268D02*
X596525Y-75407D01*
X595930Y-75805D01*
X595532Y-76401D01*
X595392Y-77103D01*
X595532Y-77805D01*
X595930Y-78401D01*
X596525Y-78799D01*
X597227Y-78938D01*
X597930Y-78799D01*
X598525Y-78401D01*
X598923Y-77805D01*
X599063Y-77103D01*
X598923Y-76401D01*
X598525Y-75805D01*
X597930Y-75407D01*
X597227Y-75268D01*
D02*
G37*
G36*
X618898Y-80448D02*
X618195Y-80588D01*
X617600Y-80986D01*
X617202Y-81581D01*
X617062Y-82284D01*
X617202Y-82986D01*
X617600Y-83581D01*
X618195Y-83979D01*
X618898Y-84119D01*
X619600Y-83979D01*
X620195Y-83581D01*
X620593Y-82986D01*
X620733Y-82284D01*
X620593Y-81581D01*
X620195Y-80986D01*
X619600Y-80588D01*
X618898Y-80448D01*
D02*
G37*
G36*
X599279Y-81146D02*
X598576Y-81285D01*
X597981Y-81683D01*
X597583Y-82278D01*
X597443Y-82981D01*
X597583Y-83683D01*
X597981Y-84278D01*
X598576Y-84676D01*
X599279Y-84816D01*
X599981Y-84676D01*
X600576Y-84278D01*
X600974Y-83683D01*
X601114Y-82981D01*
X600974Y-82278D01*
X600576Y-81683D01*
X599981Y-81285D01*
X599279Y-81146D01*
D02*
G37*
G36*
X578168Y-78943D02*
X577465Y-79083D01*
X576870Y-79480D01*
X576472Y-80076D01*
X576332Y-80778D01*
X576472Y-81480D01*
X576750Y-81896D01*
X576710Y-82524D01*
X576655Y-82561D01*
X576257Y-83156D01*
X576118Y-83858D01*
X576257Y-84561D01*
X576655Y-85156D01*
X577250Y-85554D01*
X577953Y-85694D01*
X578655Y-85554D01*
X579250Y-85156D01*
X579648Y-84561D01*
X579788Y-83858D01*
X579648Y-83156D01*
X579327Y-82675D01*
X579411Y-82112D01*
X579465Y-82076D01*
X579863Y-81480D01*
X580003Y-80778D01*
X579863Y-80076D01*
X579465Y-79480D01*
X578870Y-79083D01*
X578168Y-78943D01*
D02*
G37*
G36*
X612205Y-85173D02*
X611502Y-85312D01*
X610907Y-85710D01*
X610509Y-86306D01*
X610369Y-87008D01*
X610509Y-87710D01*
X610907Y-88306D01*
X611502Y-88703D01*
X612205Y-88843D01*
X612907Y-88703D01*
X613502Y-88306D01*
X613900Y-87710D01*
X614040Y-87008D01*
X613900Y-86306D01*
X613502Y-85710D01*
X612907Y-85312D01*
X612205Y-85173D01*
D02*
G37*
G36*
X568504Y-86354D02*
X567802Y-86493D01*
X567206Y-86891D01*
X566808Y-87487D01*
X566669Y-88189D01*
X566808Y-88891D01*
X567206Y-89487D01*
X567802Y-89885D01*
X568504Y-90024D01*
X569206Y-89885D01*
X569802Y-89487D01*
X570199Y-88891D01*
X570339Y-88189D01*
X570199Y-87487D01*
X569802Y-86891D01*
X569206Y-86493D01*
X568504Y-86354D01*
D02*
G37*
G36*
X366929Y-74149D02*
X366227Y-74289D01*
X365631Y-74686D01*
X365234Y-75282D01*
X365094Y-75984D01*
X365234Y-76687D01*
X365631Y-77282D01*
X365891Y-77455D01*
Y-78057D01*
X365631Y-78230D01*
X365234Y-78825D01*
X365094Y-79528D01*
X365234Y-80230D01*
X365631Y-80825D01*
X365891Y-80998D01*
Y-81600D01*
X365631Y-81773D01*
X365234Y-82369D01*
X365094Y-83071D01*
X365234Y-83773D01*
X365631Y-84369D01*
X365891Y-84542D01*
Y-85143D01*
X365631Y-85316D01*
X365234Y-85912D01*
X365094Y-86614D01*
X365234Y-87317D01*
X365631Y-87912D01*
Y-88072D01*
X365234Y-88668D01*
X365094Y-89370D01*
X365234Y-90072D01*
X365631Y-90668D01*
X366227Y-91066D01*
X366929Y-91205D01*
X367631Y-91066D01*
X368227Y-90668D01*
X368625Y-90072D01*
X368764Y-89370D01*
X368625Y-88668D01*
X368227Y-88072D01*
Y-87912D01*
X368625Y-87317D01*
X368764Y-86614D01*
X368625Y-85912D01*
X368227Y-85316D01*
X367968Y-85143D01*
Y-84542D01*
X368227Y-84369D01*
X368625Y-83773D01*
X368764Y-83071D01*
X368625Y-82369D01*
X368227Y-81773D01*
X367968Y-81600D01*
Y-80998D01*
X368227Y-80825D01*
X368625Y-80230D01*
X368764Y-79528D01*
X368625Y-78825D01*
X368227Y-78230D01*
X367968Y-78057D01*
Y-77455D01*
X368227Y-77282D01*
X368625Y-76687D01*
X368764Y-75984D01*
X368625Y-75282D01*
X368227Y-74686D01*
X367631Y-74289D01*
X366929Y-74149D01*
D02*
G37*
G36*
X104528Y-90339D02*
X103825Y-90479D01*
X103230Y-90877D01*
X102832Y-91473D01*
X102692Y-92175D01*
X102832Y-92877D01*
X103230Y-93472D01*
X103825Y-93870D01*
X104528Y-94010D01*
X105230Y-93870D01*
X105825Y-93472D01*
X106223Y-92877D01*
X106363Y-92175D01*
X106223Y-91473D01*
X105825Y-90877D01*
X105230Y-90479D01*
X104528Y-90339D01*
D02*
G37*
G36*
X623228Y-91472D02*
X622526Y-91611D01*
X621931Y-92009D01*
X621533Y-92605D01*
X621393Y-93307D01*
X621533Y-94009D01*
X621931Y-94605D01*
X622526Y-95003D01*
X623228Y-95142D01*
X623931Y-95003D01*
X624526Y-94605D01*
X624924Y-94009D01*
X625064Y-93307D01*
X624924Y-92605D01*
X624526Y-92009D01*
X623931Y-91611D01*
X623228Y-91472D01*
D02*
G37*
G36*
X592520D02*
X591817Y-91611D01*
X591222Y-92009D01*
X590824Y-92605D01*
X590684Y-93307D01*
X590824Y-94009D01*
X591222Y-94605D01*
X591817Y-95003D01*
X592520Y-95142D01*
X593222Y-95003D01*
X593817Y-94605D01*
X594215Y-94009D01*
X594355Y-93307D01*
X594215Y-92605D01*
X593817Y-92009D01*
X593222Y-91611D01*
X592520Y-91472D01*
D02*
G37*
G36*
X567323Y-92259D02*
X566620Y-92399D01*
X566025Y-92797D01*
X565627Y-93392D01*
X565488Y-94095D01*
X565627Y-94797D01*
X566025Y-95392D01*
X566620Y-95790D01*
X567323Y-95930D01*
X568025Y-95790D01*
X568621Y-95392D01*
X569018Y-94797D01*
X569158Y-94095D01*
X569018Y-93392D01*
X568621Y-92797D01*
X568025Y-92399D01*
X567323Y-92259D01*
D02*
G37*
G36*
X601745Y-96215D02*
X601042Y-96355D01*
X600447Y-96753D01*
X600049Y-97348D01*
X599909Y-98051D01*
X600049Y-98753D01*
X600447Y-99348D01*
X601042Y-99746D01*
X601745Y-99886D01*
X602447Y-99746D01*
X603042Y-99348D01*
X603440Y-98753D01*
X603580Y-98051D01*
X603440Y-97348D01*
X603042Y-96753D01*
X602447Y-96355D01*
X601745Y-96215D01*
D02*
G37*
G36*
X612598Y-98165D02*
X611896Y-98304D01*
X611301Y-98702D01*
X610903Y-99298D01*
X610763Y-100000D01*
X610903Y-100702D01*
X611301Y-101298D01*
X611896Y-101696D01*
X612598Y-101835D01*
X613301Y-101696D01*
X613896Y-101298D01*
X614294Y-100702D01*
X614434Y-100000D01*
X614294Y-99298D01*
X613896Y-98702D01*
X613301Y-98304D01*
X612598Y-98165D01*
D02*
G37*
G36*
X620959Y-98212D02*
X620257Y-98352D01*
X619661Y-98750D01*
X619263Y-99345D01*
X619124Y-100047D01*
X619263Y-100750D01*
X619661Y-101345D01*
X620257Y-101743D01*
X620959Y-101883D01*
X621661Y-101743D01*
X622257Y-101345D01*
X622654Y-100750D01*
X622794Y-100047D01*
X622654Y-99345D01*
X622257Y-98750D01*
X621661Y-98352D01*
X620959Y-98212D01*
D02*
G37*
G36*
X588372Y-99109D02*
X587670Y-99249D01*
X587075Y-99647D01*
X586677Y-100242D01*
X586537Y-100945D01*
X586677Y-101647D01*
X587075Y-102242D01*
X587670Y-102640D01*
X588372Y-102780D01*
X589075Y-102640D01*
X589670Y-102242D01*
X590068Y-101647D01*
X590207Y-100945D01*
X590068Y-100242D01*
X589670Y-99647D01*
X589075Y-99249D01*
X588372Y-99109D01*
D02*
G37*
G36*
X579921Y-100133D02*
X579219Y-100273D01*
X578623Y-100671D01*
X578226Y-101266D01*
X578086Y-101969D01*
X578226Y-102671D01*
X578623Y-103266D01*
X579219Y-103664D01*
X579921Y-103804D01*
X580624Y-103664D01*
X581219Y-103266D01*
X581617Y-102671D01*
X581756Y-101969D01*
X581617Y-101266D01*
X581219Y-100671D01*
X580624Y-100273D01*
X579921Y-100133D01*
D02*
G37*
G36*
X435827Y-101708D02*
X435124Y-101848D01*
X434529Y-102246D01*
X434131Y-102841D01*
X433991Y-103543D01*
X434131Y-104246D01*
X434529Y-104841D01*
X435124Y-105239D01*
X435827Y-105379D01*
X436529Y-105239D01*
X437124Y-104841D01*
X437522Y-104246D01*
X437662Y-103543D01*
X437522Y-102841D01*
X437124Y-102246D01*
X436529Y-101848D01*
X435827Y-101708D01*
D02*
G37*
G36*
X310069Y-83916D02*
X308343Y-84052D01*
X306659Y-84456D01*
X305060Y-85119D01*
X303583Y-86024D01*
X302267Y-87148D01*
X301142Y-88465D01*
X300238Y-89941D01*
X299575Y-91541D01*
X299171Y-93224D01*
X299035Y-94950D01*
X299171Y-96676D01*
X299575Y-98360D01*
X300238Y-99960D01*
X301142Y-101436D01*
X302267Y-102753D01*
X303583Y-103877D01*
X305060Y-104782D01*
X306659Y-105444D01*
X308343Y-105849D01*
X310069Y-105984D01*
X311795Y-105849D01*
X313479Y-105444D01*
X315078Y-104782D01*
X316555Y-103877D01*
X317871Y-102753D01*
X318996Y-101436D01*
X319900Y-99960D01*
X320563Y-98360D01*
X320967Y-96676D01*
X321103Y-94950D01*
X320967Y-93224D01*
X320563Y-91541D01*
X319900Y-89941D01*
X318996Y-88465D01*
X317871Y-87148D01*
X316555Y-86024D01*
X315078Y-85119D01*
X313479Y-84456D01*
X311795Y-84052D01*
X310069Y-83916D01*
D02*
G37*
G36*
X71880D02*
X70154Y-84052D01*
X68470Y-84456D01*
X66871Y-85119D01*
X65394Y-86024D01*
X64078Y-87148D01*
X62953Y-88465D01*
X62049Y-89941D01*
X61386Y-91541D01*
X60982Y-93224D01*
X60846Y-94950D01*
X60982Y-96676D01*
X61386Y-98360D01*
X62049Y-99960D01*
X62953Y-101436D01*
X64078Y-102753D01*
X65394Y-103877D01*
X66871Y-104782D01*
X68470Y-105444D01*
X70154Y-105849D01*
X71880Y-105984D01*
X73606Y-105849D01*
X75290Y-105444D01*
X76889Y-104782D01*
X78366Y-103877D01*
X79682Y-102753D01*
X80807Y-101436D01*
X81711Y-99960D01*
X82374Y-98360D01*
X82778Y-96676D01*
X82914Y-94950D01*
X82778Y-93224D01*
X82374Y-91541D01*
X81711Y-89941D01*
X80807Y-88465D01*
X79682Y-87148D01*
X78366Y-86024D01*
X76889Y-85119D01*
X75290Y-84456D01*
X73606Y-84052D01*
X71880Y-83916D01*
D02*
G37*
G36*
X512795Y-102379D02*
X512093Y-102519D01*
X511497Y-102917D01*
X511100Y-103512D01*
X510960Y-104214D01*
X511100Y-104917D01*
X511497Y-105512D01*
X512093Y-105910D01*
X512795Y-106049D01*
X513498Y-105910D01*
X514093Y-105512D01*
X514491Y-104917D01*
X514631Y-104214D01*
X514491Y-103512D01*
X514093Y-102917D01*
X513498Y-102519D01*
X512795Y-102379D01*
D02*
G37*
G36*
X651545Y-84074D02*
X649819Y-84210D01*
X648136Y-84614D01*
X646536Y-85276D01*
X645060Y-86181D01*
X643743Y-87306D01*
X642619Y-88622D01*
X641714Y-90099D01*
X641051Y-91698D01*
X640647Y-93382D01*
X640511Y-95108D01*
X640647Y-96834D01*
X641051Y-98518D01*
X641714Y-100117D01*
X642619Y-101593D01*
X643743Y-102910D01*
X645060Y-104034D01*
X646536Y-104939D01*
X648136Y-105602D01*
X649819Y-106006D01*
X651545Y-106142D01*
X653271Y-106006D01*
X654955Y-105602D01*
X656555Y-104939D01*
X658031Y-104034D01*
X659347Y-102910D01*
X660472Y-101593D01*
X661377Y-100117D01*
X662039Y-98518D01*
X662443Y-96834D01*
X662579Y-95108D01*
X662443Y-93382D01*
X662039Y-91698D01*
X661377Y-90099D01*
X660472Y-88622D01*
X659347Y-87306D01*
X658031Y-86181D01*
X656555Y-85276D01*
X654955Y-84614D01*
X653271Y-84210D01*
X651545Y-84074D01*
D02*
G37*
G36*
X413356D02*
X411630Y-84210D01*
X409947Y-84614D01*
X408347Y-85276D01*
X406871Y-86181D01*
X405554Y-87306D01*
X404430Y-88622D01*
X403525Y-90099D01*
X402862Y-91698D01*
X402458Y-93382D01*
X402322Y-95108D01*
X402458Y-96834D01*
X402862Y-98518D01*
X403525Y-100117D01*
X404430Y-101593D01*
X405554Y-102910D01*
X406871Y-104034D01*
X408347Y-104939D01*
X409947Y-105602D01*
X411630Y-106006D01*
X413356Y-106142D01*
X415082Y-106006D01*
X416766Y-105602D01*
X418366Y-104939D01*
X419842Y-104034D01*
X421159Y-102910D01*
X422283Y-101593D01*
X423188Y-100117D01*
X423850Y-98518D01*
X424254Y-96834D01*
X424390Y-95108D01*
X424254Y-93382D01*
X423850Y-91698D01*
X423188Y-90099D01*
X422283Y-88622D01*
X421159Y-87306D01*
X419842Y-86181D01*
X418366Y-85276D01*
X416766Y-84614D01*
X415082Y-84210D01*
X413356Y-84074D01*
D02*
G37*
G36*
X228824Y-103015D02*
X228121Y-103154D01*
X227526Y-103552D01*
X227128Y-104148D01*
X226989Y-104850D01*
X227128Y-105552D01*
X227526Y-106148D01*
X228121Y-106545D01*
X228824Y-106685D01*
X229526Y-106545D01*
X230121Y-106148D01*
X230519Y-105552D01*
X230659Y-104850D01*
X230519Y-104148D01*
X230121Y-103552D01*
X229526Y-103154D01*
X228824Y-103015D01*
D02*
G37*
G36*
X483484Y-104004D02*
X482782Y-104144D01*
X482186Y-104542D01*
X481788Y-105137D01*
X481649Y-105840D01*
X481788Y-106542D01*
X482186Y-107137D01*
X482782Y-107535D01*
X483484Y-107675D01*
X484186Y-107535D01*
X484782Y-107137D01*
X485180Y-106542D01*
X485319Y-105840D01*
X485180Y-105137D01*
X484782Y-104542D01*
X484186Y-104144D01*
X483484Y-104004D01*
D02*
G37*
G36*
X473228Y-104070D02*
X472526Y-104210D01*
X471931Y-104608D01*
X471533Y-105203D01*
X471393Y-105905D01*
X471533Y-106608D01*
X471931Y-107203D01*
X472526Y-107601D01*
X473228Y-107741D01*
X473931Y-107601D01*
X474526Y-107203D01*
X474924Y-106608D01*
X475064Y-105905D01*
X474924Y-105203D01*
X474526Y-104608D01*
X473931Y-104210D01*
X473228Y-104070D01*
D02*
G37*
G36*
X269685Y-104316D02*
X268983Y-104456D01*
X268387Y-104853D01*
X267989Y-105449D01*
X267850Y-106151D01*
X267989Y-106853D01*
X268387Y-107449D01*
X268983Y-107847D01*
X269685Y-107986D01*
X270387Y-107847D01*
X270983Y-107449D01*
X271381Y-106853D01*
X271520Y-106151D01*
X271381Y-105449D01*
X270983Y-104853D01*
X270387Y-104456D01*
X269685Y-104316D01*
D02*
G37*
G36*
X504703Y-104837D02*
X504001Y-104977D01*
X503406Y-105375D01*
X503008Y-105970D01*
X502868Y-106672D01*
X503008Y-107375D01*
X503406Y-107970D01*
X504001Y-108368D01*
X504703Y-108508D01*
X505406Y-108368D01*
X506001Y-107970D01*
X506399Y-107375D01*
X506539Y-106672D01*
X506399Y-105970D01*
X506001Y-105375D01*
X505406Y-104977D01*
X504703Y-104837D01*
D02*
G37*
G36*
X667717Y-104858D02*
X667014Y-104997D01*
X666419Y-105395D01*
X666021Y-105991D01*
X665881Y-106693D01*
X666021Y-107395D01*
X666419Y-107991D01*
X667014Y-108388D01*
X667717Y-108528D01*
X668419Y-108388D01*
X669014Y-107991D01*
X669412Y-107395D01*
X669552Y-106693D01*
X669412Y-105991D01*
X669014Y-105395D01*
X668419Y-104997D01*
X667717Y-104858D01*
D02*
G37*
G36*
X377165Y-105448D02*
X376463Y-105588D01*
X375868Y-105986D01*
X375470Y-106581D01*
X375330Y-107283D01*
X375470Y-107986D01*
X375868Y-108581D01*
X376463Y-108979D01*
X377165Y-109119D01*
X377868Y-108979D01*
X378430Y-108604D01*
X378577Y-108542D01*
X378990D01*
X379041Y-108618D01*
X379636Y-109016D01*
X380339Y-109156D01*
X381041Y-109016D01*
X381595Y-108646D01*
X382126Y-108717D01*
X382167Y-108778D01*
X382762Y-109176D01*
X383465Y-109316D01*
X384167Y-109176D01*
X384762Y-108778D01*
X385160Y-108183D01*
X385300Y-107480D01*
X385160Y-106778D01*
X384762Y-106183D01*
X384167Y-105785D01*
X383465Y-105645D01*
X382762Y-105785D01*
X382208Y-106155D01*
X381677Y-106084D01*
X381636Y-106023D01*
X381041Y-105625D01*
X380339Y-105485D01*
X379636Y-105625D01*
X379074Y-106001D01*
X378927Y-106063D01*
X378514D01*
X378463Y-105986D01*
X377868Y-105588D01*
X377165Y-105448D01*
D02*
G37*
G36*
X107346Y-108401D02*
X106644Y-108541D01*
X106049Y-108939D01*
X105651Y-109534D01*
X105511Y-110236D01*
X105040Y-110430D01*
X104644Y-110509D01*
X104049Y-110907D01*
X103651Y-111502D01*
X103570Y-111910D01*
X103060D01*
X102979Y-111502D01*
X102581Y-110907D01*
X101986Y-110509D01*
X101651Y-110442D01*
X101182Y-110236D01*
X101042Y-109534D01*
X100644Y-108939D01*
X100049Y-108541D01*
X99347Y-108401D01*
X98644Y-108541D01*
X98049Y-108939D01*
X97651Y-109534D01*
X97575Y-109918D01*
X97284Y-110370D01*
X96581Y-110509D01*
X95986Y-110907D01*
X95588Y-111502D01*
X95448Y-112205D01*
X95588Y-112907D01*
X95986Y-113502D01*
X96581Y-113900D01*
X97284Y-114040D01*
X97986Y-113900D01*
X98581Y-113502D01*
X98979Y-112907D01*
X99029Y-112658D01*
X99538D01*
X99588Y-112907D01*
X99986Y-113502D01*
X100581Y-113900D01*
X101284Y-114040D01*
X101986Y-113900D01*
X102581Y-113502D01*
X102979Y-112907D01*
X103060Y-112500D01*
X103570D01*
X103651Y-112907D01*
X104049Y-113502D01*
X104644Y-113900D01*
X105347Y-114040D01*
X106049Y-113900D01*
X106644Y-113502D01*
X107042Y-112907D01*
X107120Y-112515D01*
X107630D01*
X107714Y-112938D01*
X108112Y-113534D01*
X108707Y-113932D01*
X109409Y-114072D01*
X110112Y-113932D01*
X110707Y-113534D01*
X111105Y-112938D01*
X111245Y-112236D01*
X111105Y-111534D01*
X110707Y-110939D01*
X110112Y-110541D01*
X109649Y-110449D01*
X109182Y-110236D01*
X109042Y-109534D01*
X108644Y-108939D01*
X108049Y-108541D01*
X107346Y-108401D01*
D02*
G37*
G36*
X354724Y-111944D02*
X354022Y-112084D01*
X353740Y-112272D01*
X353458Y-112084D01*
X352756Y-111944D01*
X352054Y-112084D01*
X351772Y-112272D01*
X351490Y-112084D01*
X350787Y-111944D01*
X350085Y-112084D01*
X349490Y-112482D01*
X349092Y-113077D01*
X348952Y-113779D01*
X349092Y-114482D01*
X349490Y-115077D01*
X349530Y-115104D01*
Y-115604D01*
X349490Y-115631D01*
X349092Y-116227D01*
X348952Y-116929D01*
X349092Y-117631D01*
X349490Y-118227D01*
X350085Y-118625D01*
X350787Y-118764D01*
X351490Y-118625D01*
X351772Y-118436D01*
X352054Y-118625D01*
X352756Y-118764D01*
X353458Y-118625D01*
X353740Y-118436D01*
X354022Y-118625D01*
X354724Y-118764D01*
X355427Y-118625D01*
X356022Y-118227D01*
X356420Y-117631D01*
X356560Y-116929D01*
X356420Y-116227D01*
X356022Y-115631D01*
X355982Y-115604D01*
Y-115104D01*
X356022Y-115077D01*
X356420Y-114482D01*
X356560Y-113779D01*
X356420Y-113077D01*
X356022Y-112482D01*
X355427Y-112084D01*
X354724Y-111944D01*
D02*
G37*
G36*
X443307Y-109188D02*
X442605Y-109328D01*
X442009Y-109726D01*
X441611Y-110321D01*
X441472Y-111024D01*
X441611Y-111726D01*
X442009Y-112321D01*
X442605Y-112719D01*
X443307Y-112859D01*
X444009Y-112719D01*
X444605Y-112321D01*
X445003Y-111726D01*
X445142Y-111024D01*
X445003Y-110321D01*
X444605Y-109726D01*
X444009Y-109328D01*
X443307Y-109188D01*
D02*
G37*
G36*
X246063D02*
X245361Y-109328D01*
X244765Y-109726D01*
X244367Y-110321D01*
X244228Y-111024D01*
X244367Y-111726D01*
X244765Y-112321D01*
X245361Y-112719D01*
X246063Y-112859D01*
X246765Y-112719D01*
X247361Y-112321D01*
X247759Y-111726D01*
X247898Y-111024D01*
X247759Y-110321D01*
X247361Y-109726D01*
X246765Y-109328D01*
X246063Y-109188D01*
D02*
G37*
G36*
X253690Y-110125D02*
X252988Y-110264D01*
X252392Y-110662D01*
X251994Y-111258D01*
X251855Y-111960D01*
X251994Y-112662D01*
X252392Y-113258D01*
X252988Y-113655D01*
X253690Y-113795D01*
X254392Y-113655D01*
X254976Y-113266D01*
X255100Y-113195D01*
X255530D01*
X255599Y-113298D01*
X256194Y-113696D01*
X256897Y-113836D01*
X257599Y-113696D01*
X258195Y-113298D01*
X258592Y-112703D01*
X258732Y-112001D01*
X258592Y-111298D01*
X258195Y-110703D01*
X257599Y-110305D01*
X256897Y-110165D01*
X256194Y-110305D01*
X255599Y-110703D01*
X255557Y-110766D01*
X255057D01*
X254988Y-110662D01*
X254392Y-110264D01*
X253690Y-110125D01*
D02*
G37*
G36*
X402719Y-110498D02*
X402016Y-110638D01*
X401421Y-111036D01*
X401023Y-111631D01*
X400883Y-112334D01*
X401023Y-113036D01*
X401421Y-113631D01*
X402016Y-114029D01*
X402719Y-114169D01*
X403421Y-114029D01*
X404016Y-113631D01*
X404414Y-113036D01*
X404554Y-112334D01*
X404414Y-111631D01*
X404016Y-111036D01*
X403421Y-110638D01*
X402719Y-110498D01*
D02*
G37*
G36*
X62986Y-110968D02*
X62284Y-111107D01*
X61689Y-111505D01*
X61291Y-112101D01*
X61151Y-112803D01*
X61291Y-113505D01*
X61689Y-114101D01*
X62284Y-114498D01*
X62986Y-114638D01*
X63689Y-114498D01*
X64284Y-114101D01*
X64682Y-113505D01*
X64822Y-112803D01*
X64682Y-112101D01*
X64284Y-111505D01*
X63689Y-111107D01*
X62986Y-110968D01*
D02*
G37*
G36*
X472441Y-111944D02*
X471739Y-112084D01*
X471143Y-112482D01*
X470745Y-113077D01*
X470606Y-113779D01*
X470745Y-114482D01*
X471143Y-115077D01*
X471739Y-115475D01*
X472441Y-115615D01*
X473143Y-115475D01*
X473739Y-115077D01*
X474136Y-114482D01*
X474276Y-113779D01*
X474136Y-113077D01*
X473739Y-112482D01*
X473143Y-112084D01*
X472441Y-111944D01*
D02*
G37*
G36*
X309016Y-112151D02*
X308313Y-112290D01*
X307718Y-112688D01*
X307320Y-113284D01*
X307181Y-113986D01*
X307320Y-114688D01*
X307718Y-115284D01*
X308313Y-115681D01*
X309016Y-115821D01*
X309718Y-115681D01*
X310314Y-115284D01*
X310711Y-114688D01*
X310851Y-113986D01*
X310711Y-113284D01*
X310314Y-112688D01*
X309718Y-112290D01*
X309016Y-112151D01*
D02*
G37*
G36*
X-23622Y-100527D02*
X-24324Y-100667D01*
X-24920Y-101065D01*
X-25318Y-101660D01*
X-25457Y-102362D01*
X-25318Y-103065D01*
X-24920Y-103660D01*
X-24324Y-104058D01*
X-24234Y-104076D01*
Y-104586D01*
X-24324Y-104604D01*
X-24920Y-105001D01*
X-25318Y-105597D01*
X-25457Y-106299D01*
X-25318Y-107001D01*
X-24920Y-107597D01*
X-24324Y-107995D01*
X-24234Y-108013D01*
Y-108523D01*
X-24324Y-108541D01*
X-24920Y-108939D01*
X-25318Y-109534D01*
X-25457Y-110236D01*
X-25318Y-110939D01*
X-24920Y-111534D01*
X-24324Y-111932D01*
X-24234Y-111950D01*
Y-112460D01*
X-24324Y-112478D01*
X-24920Y-112875D01*
X-25318Y-113471D01*
X-25457Y-114173D01*
X-25318Y-114875D01*
X-24920Y-115471D01*
X-24324Y-115869D01*
X-23622Y-116008D01*
X-22920Y-115869D01*
X-22324Y-115471D01*
X-21926Y-114875D01*
X-21787Y-114173D01*
X-21926Y-113471D01*
X-22324Y-112875D01*
X-22920Y-112478D01*
X-23010Y-112460D01*
Y-111950D01*
X-22920Y-111932D01*
X-22324Y-111534D01*
X-21926Y-110939D01*
X-21787Y-110236D01*
X-21926Y-109534D01*
X-22324Y-108939D01*
X-22920Y-108541D01*
X-23010Y-108523D01*
Y-108013D01*
X-22920Y-107995D01*
X-22324Y-107597D01*
X-21926Y-107001D01*
X-21787Y-106299D01*
X-21926Y-105597D01*
X-22324Y-105001D01*
X-22920Y-104604D01*
X-23010Y-104586D01*
Y-104076D01*
X-22920Y-104058D01*
X-22324Y-103660D01*
X-21926Y-103065D01*
X-21787Y-102362D01*
X-21926Y-101660D01*
X-22324Y-101065D01*
X-22920Y-100667D01*
X-23622Y-100527D01*
D02*
G37*
G36*
X193898Y-113174D02*
X193195Y-113314D01*
X192600Y-113712D01*
X192202Y-114307D01*
X192062Y-115009D01*
X192202Y-115712D01*
X192600Y-116307D01*
X193195Y-116705D01*
X193898Y-116845D01*
X194600Y-116705D01*
X195195Y-116307D01*
X195593Y-115712D01*
X195733Y-115009D01*
X195593Y-114307D01*
X195195Y-113712D01*
X194600Y-113314D01*
X193898Y-113174D01*
D02*
G37*
G36*
X538583Y-109976D02*
X537880Y-110116D01*
X537285Y-110513D01*
X536887Y-111109D01*
X536747Y-111811D01*
X536887Y-112513D01*
X537285Y-113109D01*
X537880Y-113507D01*
X538346Y-113599D01*
X538401Y-114120D01*
X537935Y-114431D01*
X537537Y-115027D01*
X537398Y-115729D01*
X537537Y-116431D01*
X537935Y-117027D01*
X538531Y-117425D01*
X539233Y-117564D01*
X539935Y-117425D01*
X540531Y-117027D01*
X540928Y-116431D01*
X541068Y-115729D01*
X540928Y-115027D01*
X540531Y-114431D01*
X539935Y-114033D01*
X539470Y-113941D01*
X539414Y-113420D01*
X539880Y-113109D01*
X540278Y-112513D01*
X540418Y-111811D01*
X540278Y-111109D01*
X539880Y-110513D01*
X539285Y-110116D01*
X538583Y-109976D01*
D02*
G37*
G36*
X463551Y-114190D02*
X462849Y-114330D01*
X462254Y-114727D01*
X461856Y-115323D01*
X461716Y-116025D01*
X461856Y-116727D01*
X462254Y-117323D01*
X462849Y-117721D01*
X463551Y-117860D01*
X464254Y-117721D01*
X464849Y-117323D01*
X465247Y-116727D01*
X465386Y-116025D01*
X465247Y-115323D01*
X464849Y-114727D01*
X464254Y-114330D01*
X463551Y-114190D01*
D02*
G37*
G36*
X456742Y-114208D02*
X456040Y-114347D01*
X455444Y-114745D01*
X455047Y-115341D01*
X454907Y-116043D01*
X455047Y-116745D01*
X455444Y-117341D01*
X456040Y-117738D01*
X456742Y-117878D01*
X457444Y-117738D01*
X458040Y-117341D01*
X458438Y-116745D01*
X458577Y-116043D01*
X458438Y-115341D01*
X458040Y-114745D01*
X457444Y-114347D01*
X456742Y-114208D01*
D02*
G37*
G36*
X238189Y-114306D02*
X237487Y-114446D01*
X236891Y-114844D01*
X236493Y-115439D01*
X236354Y-116142D01*
X236493Y-116844D01*
X236891Y-117439D01*
X237487Y-117837D01*
X238189Y-117977D01*
X238891Y-117837D01*
X239487Y-117439D01*
X239884Y-116844D01*
X240024Y-116142D01*
X239884Y-115439D01*
X239487Y-114844D01*
X238891Y-114446D01*
X238189Y-114306D01*
D02*
G37*
G36*
X508268Y-115488D02*
X507565Y-115627D01*
X506970Y-116025D01*
X506572Y-116621D01*
X506432Y-117323D01*
X506572Y-118025D01*
X506970Y-118621D01*
X507565Y-119018D01*
X508268Y-119158D01*
X508970Y-119018D01*
X509565Y-118621D01*
X509963Y-118025D01*
X510103Y-117323D01*
X509963Y-116621D01*
X509565Y-116025D01*
X508970Y-115627D01*
X508268Y-115488D01*
D02*
G37*
G36*
X533878Y-115881D02*
X533176Y-116021D01*
X532580Y-116418D01*
X532183Y-117014D01*
X532043Y-117716D01*
X532183Y-118419D01*
X532580Y-119014D01*
X533176Y-119412D01*
X533878Y-119551D01*
X534580Y-119412D01*
X535176Y-119014D01*
X535574Y-118419D01*
X535713Y-117716D01*
X535574Y-117014D01*
X535176Y-116418D01*
X534580Y-116021D01*
X533878Y-115881D01*
D02*
G37*
G36*
X255118Y-116669D02*
X254416Y-116808D01*
X253820Y-117206D01*
X253423Y-117802D01*
X253283Y-118504D01*
X253423Y-119206D01*
X253820Y-119802D01*
X254416Y-120200D01*
X255118Y-120339D01*
X255820Y-120200D01*
X256416Y-119802D01*
X256814Y-119206D01*
X256953Y-118504D01*
X256814Y-117802D01*
X256416Y-117206D01*
X255820Y-116808D01*
X255118Y-116669D01*
D02*
G37*
G36*
X314961Y-117111D02*
X314258Y-117251D01*
X313663Y-117649D01*
X313265Y-118244D01*
X313125Y-118947D01*
X313265Y-119649D01*
X313663Y-120244D01*
X314258Y-120642D01*
X314961Y-120782D01*
X315663Y-120642D01*
X316258Y-120244D01*
X316656Y-119649D01*
X316796Y-118947D01*
X316656Y-118244D01*
X316258Y-117649D01*
X315663Y-117251D01*
X314961Y-117111D01*
D02*
G37*
G36*
X193898Y-118095D02*
X193195Y-118235D01*
X192600Y-118633D01*
X192202Y-119228D01*
X192062Y-119931D01*
X192202Y-120633D01*
X192600Y-121228D01*
X193195Y-121626D01*
X193898Y-121766D01*
X194600Y-121626D01*
X195195Y-121228D01*
X195593Y-120633D01*
X195733Y-119931D01*
X195593Y-119228D01*
X195195Y-118633D01*
X194600Y-118235D01*
X193898Y-118095D01*
D02*
G37*
G36*
X70866Y-120212D02*
X70164Y-120352D01*
X69568Y-120749D01*
X69171Y-121345D01*
X69031Y-122047D01*
X69171Y-122750D01*
X69568Y-123345D01*
X70164Y-123743D01*
X70866Y-123882D01*
X71569Y-123743D01*
X72164Y-123345D01*
X72562Y-122750D01*
X72701Y-122047D01*
X72562Y-121345D01*
X72164Y-120749D01*
X71569Y-120352D01*
X70866Y-120212D01*
D02*
G37*
G36*
X185547Y-116028D02*
X177445D01*
Y-124130D01*
X185547D01*
Y-116028D01*
D02*
G37*
G36*
X161496Y-115993D02*
X160439Y-116132D01*
X159453Y-116540D01*
X158607Y-117189D01*
X157957Y-118036D01*
X157549Y-119021D01*
X157410Y-120079D01*
X157549Y-121136D01*
X157957Y-122122D01*
X158607Y-122968D01*
X159453Y-123617D01*
X160439Y-124026D01*
X161496Y-124165D01*
X162554Y-124026D01*
X163539Y-123617D01*
X164385Y-122968D01*
X165035Y-122122D01*
X165443Y-121136D01*
X165582Y-120079D01*
X165443Y-119021D01*
X165035Y-118036D01*
X164385Y-117189D01*
X163539Y-116540D01*
X162554Y-116132D01*
X161496Y-115993D01*
D02*
G37*
G36*
X151496D02*
X150438Y-116132D01*
X149453Y-116540D01*
X148607Y-117189D01*
X147957Y-118036D01*
X147549Y-119021D01*
X147410Y-120079D01*
X147549Y-121136D01*
X147957Y-122122D01*
X148607Y-122968D01*
X149453Y-123617D01*
X150438Y-124026D01*
X151496Y-124165D01*
X152554Y-124026D01*
X153539Y-123617D01*
X154385Y-122968D01*
X155035Y-122122D01*
X155443Y-121136D01*
X155582Y-120079D01*
X155443Y-119021D01*
X155035Y-118036D01*
X154385Y-117189D01*
X153539Y-116540D01*
X152554Y-116132D01*
X151496Y-115993D01*
D02*
G37*
G36*
X141496D02*
X140438Y-116132D01*
X139453Y-116540D01*
X138607Y-117189D01*
X137957Y-118036D01*
X137549Y-119021D01*
X137410Y-120079D01*
X137549Y-121136D01*
X137957Y-122122D01*
X138607Y-122968D01*
X139453Y-123617D01*
X140438Y-124026D01*
X141496Y-124165D01*
X142554Y-124026D01*
X143539Y-123617D01*
X144385Y-122968D01*
X145035Y-122122D01*
X145443Y-121136D01*
X145582Y-120079D01*
X145443Y-119021D01*
X145035Y-118036D01*
X144385Y-117189D01*
X143539Y-116540D01*
X142554Y-116132D01*
X141496Y-115993D01*
D02*
G37*
G36*
X271654Y-120999D02*
X270951Y-121139D01*
X270356Y-121537D01*
X269958Y-122132D01*
X269818Y-122835D01*
X269958Y-123537D01*
X270356Y-124132D01*
X270951Y-124530D01*
X271654Y-124670D01*
X272356Y-124530D01*
X272951Y-124132D01*
X273349Y-123537D01*
X273489Y-122835D01*
X273349Y-122132D01*
X272951Y-121537D01*
X272356Y-121139D01*
X271654Y-120999D01*
D02*
G37*
G36*
X505905Y-121787D02*
X505203Y-121926D01*
X504608Y-122324D01*
X504210Y-122920D01*
X504070Y-123622D01*
X504210Y-124324D01*
X504608Y-124920D01*
X505203Y-125318D01*
X505905Y-125457D01*
X506608Y-125318D01*
X507203Y-124920D01*
X507601Y-124324D01*
X507741Y-123622D01*
X507601Y-122920D01*
X507203Y-122324D01*
X506608Y-121926D01*
X505905Y-121787D01*
D02*
G37*
G36*
X309055Y-122032D02*
X308353Y-122172D01*
X307757Y-122570D01*
X307360Y-123165D01*
X307220Y-123868D01*
X307360Y-124570D01*
X307757Y-125165D01*
X308353Y-125563D01*
X309055Y-125703D01*
X309757Y-125563D01*
X310353Y-125165D01*
X310751Y-124570D01*
X310890Y-123868D01*
X310751Y-123165D01*
X310353Y-122570D01*
X309757Y-122172D01*
X309055Y-122032D01*
D02*
G37*
G36*
X254376Y-123911D02*
X253674Y-124051D01*
X253078Y-124449D01*
X252680Y-125044D01*
X252541Y-125747D01*
X252680Y-126449D01*
X253078Y-127044D01*
X253674Y-127442D01*
X254376Y-127582D01*
X255078Y-127442D01*
X255674Y-127044D01*
X256071Y-126449D01*
X256211Y-125747D01*
X256071Y-125044D01*
X255674Y-124449D01*
X255078Y-124051D01*
X254376Y-123911D01*
D02*
G37*
G36*
X241250Y-124412D02*
X240547Y-124551D01*
X239952Y-124949D01*
X239554Y-125545D01*
X239415Y-126247D01*
X239554Y-126949D01*
X239952Y-127545D01*
X240547Y-127942D01*
X241250Y-128082D01*
X241952Y-127942D01*
X242548Y-127545D01*
X242945Y-126949D01*
X243085Y-126247D01*
X242945Y-125545D01*
X242548Y-124949D01*
X241952Y-124551D01*
X241250Y-124412D01*
D02*
G37*
G36*
X475984Y-125330D02*
X475282Y-125470D01*
X474686Y-125868D01*
X474289Y-126463D01*
X474149Y-127165D01*
X474289Y-127868D01*
X474686Y-128463D01*
X475282Y-128861D01*
X475984Y-129001D01*
X476687Y-128861D01*
X477282Y-128463D01*
X477680Y-127868D01*
X477819Y-127165D01*
X477680Y-126463D01*
X477282Y-125868D01*
X476687Y-125470D01*
X475984Y-125330D01*
D02*
G37*
G36*
X375532Y-121774D02*
X374830Y-121914D01*
X374235Y-122312D01*
X373837Y-122907D01*
X373697Y-123610D01*
X373837Y-124312D01*
X374235Y-124908D01*
X374532Y-125106D01*
Y-125708D01*
X374293Y-125868D01*
X373895Y-126463D01*
X373755Y-127165D01*
X373895Y-127868D01*
X374293Y-128463D01*
X374888Y-128861D01*
X375590Y-129001D01*
X376293Y-128861D01*
X376888Y-128463D01*
X376915Y-128422D01*
X377328D01*
X377475Y-128485D01*
X378038Y-128861D01*
X378740Y-129001D01*
X379443Y-128861D01*
X379733Y-128667D01*
X380118Y-128498D01*
X380503Y-128667D01*
X380794Y-128861D01*
X381496Y-129001D01*
X382198Y-128861D01*
X382794Y-128463D01*
X383192Y-127868D01*
X383331Y-127165D01*
X383192Y-126463D01*
X382794Y-125868D01*
X382198Y-125470D01*
X381496Y-125330D01*
X380794Y-125470D01*
X380503Y-125664D01*
X380239Y-125780D01*
X379837Y-125552D01*
X379828Y-125060D01*
X380038Y-124920D01*
X380436Y-124324D01*
X380575Y-123622D01*
X380436Y-122920D01*
X380038Y-122324D01*
X379443Y-121926D01*
X378740Y-121787D01*
X378038Y-121926D01*
X377442Y-122324D01*
X377390Y-122402D01*
X376890D01*
X376830Y-122312D01*
X376235Y-121914D01*
X375532Y-121774D01*
D02*
G37*
G36*
X580315Y-128086D02*
X579613Y-128226D01*
X579017Y-128623D01*
X578619Y-129219D01*
X578601Y-129310D01*
X578092D01*
X578074Y-129219D01*
X577676Y-128623D01*
X577080Y-128226D01*
X576378Y-128086D01*
X575676Y-128226D01*
X575080Y-128623D01*
X574682Y-129219D01*
X574543Y-129921D01*
X574682Y-130624D01*
X575080Y-131219D01*
X575153Y-131267D01*
X574958Y-131738D01*
X574409Y-131629D01*
X573707Y-131769D01*
X573112Y-132167D01*
X573062Y-132241D01*
X572501Y-132260D01*
X572438Y-132182D01*
X572637Y-131639D01*
X572750Y-131617D01*
X573345Y-131219D01*
X573743Y-130624D01*
X573882Y-129921D01*
X573743Y-129219D01*
X573345Y-128623D01*
X572750Y-128226D01*
X572047Y-128086D01*
X571345Y-128226D01*
X570750Y-128623D01*
X570352Y-129219D01*
X570212Y-129921D01*
X570352Y-130624D01*
X570705Y-131152D01*
X570647Y-131469D01*
X570556Y-131691D01*
X570164Y-131769D01*
X569568Y-132167D01*
X569171Y-132762D01*
X569031Y-133465D01*
X569171Y-134167D01*
X569568Y-134762D01*
X570164Y-135160D01*
X570866Y-135300D01*
X571568Y-135160D01*
X572164Y-134762D01*
X572337Y-134503D01*
X572938D01*
X573112Y-134762D01*
X573707Y-135160D01*
X574409Y-135300D01*
X575112Y-135160D01*
X575707Y-134762D01*
X576105Y-134167D01*
X576245Y-133465D01*
X576105Y-132762D01*
X575707Y-132167D01*
X575635Y-132118D01*
X575830Y-131648D01*
X576378Y-131756D01*
X577080Y-131617D01*
X577676Y-131219D01*
X578074Y-130624D01*
X578092Y-130533D01*
X578601D01*
X578619Y-130624D01*
X579017Y-131219D01*
X579114Y-131284D01*
X579141Y-131410D01*
X579080Y-131862D01*
X578623Y-132167D01*
X578226Y-132762D01*
X578086Y-133465D01*
X578226Y-134167D01*
X578623Y-134762D01*
X579219Y-135160D01*
X579921Y-135300D01*
X580624Y-135160D01*
X581219Y-134762D01*
X581617Y-134167D01*
X581756Y-133465D01*
X581617Y-132762D01*
X581219Y-132167D01*
X581122Y-132102D01*
X581095Y-131976D01*
X581156Y-131524D01*
X581613Y-131219D01*
X582011Y-130624D01*
X582150Y-129921D01*
X582011Y-129219D01*
X581613Y-128623D01*
X581017Y-128226D01*
X580315Y-128086D01*
D02*
G37*
G36*
X309016Y-126824D02*
X308313Y-126963D01*
X307718Y-127361D01*
X307320Y-127957D01*
X307181Y-128659D01*
X307320Y-129361D01*
X307718Y-129957D01*
X308313Y-130355D01*
X309016Y-130494D01*
X309718Y-130355D01*
X310314Y-129957D01*
X310711Y-129361D01*
X310851Y-128659D01*
X310711Y-127957D01*
X310314Y-127361D01*
X309718Y-126963D01*
X309016Y-126824D01*
D02*
G37*
G36*
X524606Y-124001D02*
X523904Y-124141D01*
X523309Y-124539D01*
X522911Y-125134D01*
X522771Y-125836D01*
X522911Y-126539D01*
X523309Y-127134D01*
X523139Y-127622D01*
X522861Y-128037D01*
X522722Y-128740D01*
X522861Y-129442D01*
X523259Y-130037D01*
X523855Y-130435D01*
X524557Y-130575D01*
X525259Y-130435D01*
X525855Y-130037D01*
X526253Y-129442D01*
X526392Y-128740D01*
X526253Y-128037D01*
X525855Y-127442D01*
X526024Y-126954D01*
X526302Y-126539D01*
X526442Y-125836D01*
X526302Y-125134D01*
X525904Y-124539D01*
X525309Y-124141D01*
X524606Y-124001D01*
D02*
G37*
G36*
X144871Y-129774D02*
X144169Y-129914D01*
X143573Y-130312D01*
X143175Y-130907D01*
X143036Y-131609D01*
X143175Y-132312D01*
X143573Y-132907D01*
X144169Y-133305D01*
X144871Y-133444D01*
X145573Y-133305D01*
X146169Y-132907D01*
X146566Y-132312D01*
X146706Y-131609D01*
X146566Y-130907D01*
X146169Y-130312D01*
X145573Y-129914D01*
X144871Y-129774D01*
D02*
G37*
G36*
X117126Y-118086D02*
X116424Y-118226D01*
X115828Y-118623D01*
X115430Y-119219D01*
X115291Y-119921D01*
X115430Y-120624D01*
X115828Y-121219D01*
X116424Y-121617D01*
X116819Y-121695D01*
X116859Y-121727D01*
X116823Y-122263D01*
X116795Y-122277D01*
X116424Y-122351D01*
X115828Y-122749D01*
X115430Y-123344D01*
X115291Y-124047D01*
X115430Y-124749D01*
X115828Y-125344D01*
X116424Y-125742D01*
X116673Y-125792D01*
Y-126302D01*
X116424Y-126351D01*
X115828Y-126749D01*
X115430Y-127344D01*
X115291Y-128047D01*
X115430Y-128749D01*
X115828Y-129344D01*
X116424Y-129742D01*
X116674Y-129792D01*
Y-130302D01*
X116424Y-130352D01*
X115828Y-130749D01*
X115430Y-131345D01*
X115291Y-132047D01*
X115430Y-132750D01*
X115828Y-133345D01*
X116424Y-133743D01*
X117126Y-133882D01*
X117828Y-133743D01*
X118424Y-133345D01*
X118822Y-132750D01*
X118961Y-132047D01*
X119425Y-131816D01*
X119797Y-131742D01*
X120392Y-131344D01*
X120790Y-130749D01*
X120930Y-130047D01*
X120790Y-129344D01*
X120392Y-128749D01*
X119797Y-128351D01*
X119425Y-128277D01*
X118961Y-128047D01*
X118822Y-127344D01*
X118424Y-126749D01*
X117828Y-126351D01*
X117579Y-126302D01*
Y-125792D01*
X117828Y-125742D01*
X118424Y-125344D01*
X118822Y-124749D01*
X118961Y-124047D01*
X119425Y-123816D01*
X119797Y-123742D01*
X120392Y-123344D01*
X120790Y-122749D01*
X120930Y-122047D01*
X120790Y-121344D01*
X120392Y-120749D01*
X119797Y-120351D01*
X119401Y-120272D01*
X118961Y-119921D01*
X118822Y-119219D01*
X118424Y-118623D01*
X117828Y-118226D01*
X117126Y-118086D01*
D02*
G37*
G36*
X622001Y-121001D02*
X620744Y-121124D01*
X619535Y-121491D01*
X618421Y-122087D01*
X617444Y-122888D01*
X616643Y-123865D01*
X616047Y-124979D01*
X615680Y-126188D01*
X615556Y-127445D01*
X615680Y-128702D01*
X616047Y-129911D01*
X616643Y-131025D01*
X617444Y-132002D01*
X618421Y-132803D01*
X619535Y-133399D01*
X620744Y-133765D01*
X622001Y-133889D01*
X623258Y-133765D01*
X624467Y-133399D01*
X625581Y-132803D01*
X626558Y-132002D01*
X627359Y-131025D01*
X627955Y-129911D01*
X628321Y-128702D01*
X628445Y-127445D01*
X628321Y-126188D01*
X627955Y-124979D01*
X627359Y-123865D01*
X626558Y-122888D01*
X625581Y-122087D01*
X624467Y-121491D01*
X623258Y-121124D01*
X622001Y-121001D01*
D02*
G37*
G36*
X498032Y-130448D02*
X497329Y-130588D01*
X496734Y-130986D01*
X496336Y-131581D01*
X496196Y-132283D01*
X496336Y-132986D01*
X496734Y-133581D01*
X497329Y-133979D01*
X498032Y-134119D01*
X498734Y-133979D01*
X499329Y-133581D01*
X499727Y-132986D01*
X499867Y-132283D01*
X499727Y-131581D01*
X499329Y-130986D01*
X498734Y-130588D01*
X498032Y-130448D01*
D02*
G37*
G36*
X480120Y-130529D02*
X479417Y-130669D01*
X478822Y-131067D01*
X478424Y-131662D01*
X478284Y-132365D01*
X478424Y-133067D01*
X478822Y-133662D01*
X479417Y-134060D01*
X480120Y-134200D01*
X480822Y-134060D01*
X481417Y-133662D01*
X481815Y-133067D01*
X481955Y-132365D01*
X481815Y-131662D01*
X481417Y-131067D01*
X480822Y-130669D01*
X480120Y-130529D01*
D02*
G37*
G36*
X469685Y-131629D02*
X468983Y-131769D01*
X468387Y-132167D01*
X467989Y-132762D01*
X467850Y-133465D01*
X467989Y-134167D01*
X468387Y-134762D01*
X468983Y-135160D01*
X469685Y-135300D01*
X470387Y-135160D01*
X470983Y-134762D01*
X471381Y-134167D01*
X471520Y-133465D01*
X471381Y-132762D01*
X470983Y-132167D01*
X470387Y-131769D01*
X469685Y-131629D01*
D02*
G37*
G36*
X409900Y-134724D02*
X409198Y-134864D01*
X408602Y-135262D01*
X408204Y-135857D01*
X408065Y-136559D01*
X408204Y-137262D01*
X408602Y-137857D01*
X409198Y-138255D01*
X409900Y-138395D01*
X410602Y-138255D01*
X411198Y-137857D01*
X411595Y-137262D01*
X411735Y-136559D01*
X411595Y-135857D01*
X411198Y-135262D01*
X410602Y-134864D01*
X409900Y-134724D01*
D02*
G37*
G36*
X436614Y-134779D02*
X435912Y-134919D01*
X435316Y-135317D01*
X434919Y-135912D01*
X434779Y-136614D01*
X434919Y-137317D01*
X435316Y-137912D01*
X435912Y-138310D01*
X436614Y-138449D01*
X437317Y-138310D01*
X437912Y-137912D01*
X438310Y-137317D01*
X438449Y-136614D01*
X438310Y-135912D01*
X437912Y-135317D01*
X437317Y-134919D01*
X436614Y-134779D01*
D02*
G37*
G36*
X469521Y-135780D02*
X468818Y-135919D01*
X468223Y-136317D01*
X467825Y-136912D01*
X467685Y-137615D01*
X467825Y-138317D01*
X468223Y-138912D01*
X468818Y-139310D01*
X469521Y-139450D01*
X470223Y-139310D01*
X470818Y-138912D01*
X471216Y-138317D01*
X471356Y-137615D01*
X471216Y-136912D01*
X470818Y-136317D01*
X470223Y-135919D01*
X469521Y-135780D01*
D02*
G37*
G36*
X570472Y-135960D02*
X569770Y-136100D01*
X569175Y-136498D01*
X568777Y-137093D01*
X568637Y-137795D01*
X568777Y-138498D01*
X569175Y-139093D01*
X569770Y-139491D01*
X570472Y-139630D01*
X571175Y-139491D01*
X571770Y-139093D01*
X572168Y-138498D01*
X572308Y-137795D01*
X572168Y-137093D01*
X571770Y-136498D01*
X571175Y-136100D01*
X570472Y-135960D01*
D02*
G37*
G36*
X109409Y-138276D02*
X108707Y-138416D01*
X108112Y-138813D01*
X107714Y-139409D01*
X107664Y-139658D01*
X107155D01*
X107105Y-139409D01*
X106707Y-138813D01*
X106112Y-138416D01*
X105409Y-138276D01*
X104707Y-138416D01*
X104112Y-138813D01*
X103714Y-139409D01*
X103664Y-139658D01*
X103155D01*
X103105Y-139409D01*
X102707Y-138813D01*
X102112Y-138416D01*
X101409Y-138276D01*
X100707Y-138416D01*
X100112Y-138813D01*
X99714Y-139409D01*
X99664Y-139658D01*
X99155D01*
X99105Y-139409D01*
X98707Y-138813D01*
X98112Y-138416D01*
X97409Y-138276D01*
X96707Y-138416D01*
X96112Y-138813D01*
X95714Y-139409D01*
X95574Y-140111D01*
X95714Y-140813D01*
X96112Y-141409D01*
X96707Y-141807D01*
X97409Y-141946D01*
X97609Y-141907D01*
X97714Y-142435D01*
X98112Y-143030D01*
X98707Y-143428D01*
X99410Y-143568D01*
X100112Y-143428D01*
X100707Y-143030D01*
X101105Y-142435D01*
X101210Y-141907D01*
X101409Y-141946D01*
X102112Y-141807D01*
X102707Y-141409D01*
X103105Y-140813D01*
X103155Y-140564D01*
X103664D01*
X103714Y-140813D01*
X104112Y-141409D01*
X104707Y-141807D01*
X105409Y-141946D01*
X105609Y-141907D01*
X105714Y-142435D01*
X106112Y-143030D01*
X106707Y-143428D01*
X107409Y-143568D01*
X108112Y-143428D01*
X108707Y-143030D01*
X109105Y-142435D01*
X109210Y-141907D01*
X109409Y-141946D01*
X110112Y-141807D01*
X110707Y-141409D01*
X111105Y-140813D01*
X111245Y-140111D01*
X111105Y-139409D01*
X110707Y-138813D01*
X110112Y-138416D01*
X109409Y-138276D01*
D02*
G37*
G36*
X377559Y-133598D02*
X376857Y-133738D01*
X376261Y-134135D01*
X375864Y-134731D01*
X375724Y-135433D01*
X375864Y-136135D01*
X376261Y-136731D01*
X376857Y-137129D01*
X377409Y-137239D01*
X377299Y-137795D01*
X377438Y-138498D01*
X377836Y-139093D01*
X378432Y-139491D01*
X379134Y-139630D01*
X379681Y-139522D01*
X380009Y-139931D01*
X379801Y-140243D01*
X379661Y-140945D01*
X379704Y-141165D01*
X379733Y-141308D01*
X379255Y-141424D01*
X379172Y-141300D01*
X378857Y-140828D01*
X378261Y-140430D01*
X377559Y-140291D01*
X376857Y-140430D01*
X376261Y-140828D01*
X375864Y-141424D01*
X375724Y-142126D01*
X375864Y-142828D01*
X376261Y-143424D01*
X376857Y-143822D01*
X377559Y-143961D01*
X378261Y-143822D01*
X378857Y-143424D01*
X379255Y-142828D01*
X379394Y-142126D01*
X379351Y-141906D01*
X379322Y-141763D01*
X379801Y-141647D01*
X379883Y-141771D01*
X380198Y-142243D01*
X380794Y-142640D01*
X381496Y-142780D01*
X382198Y-142640D01*
X382794Y-142243D01*
X383192Y-141647D01*
X383331Y-140945D01*
X383192Y-140243D01*
X382794Y-139647D01*
X382697Y-139583D01*
X382670Y-139456D01*
X382731Y-139004D01*
X383188Y-138699D01*
X383585Y-138104D01*
X383725Y-137402D01*
X383585Y-136699D01*
X383188Y-136104D01*
X382592Y-135706D01*
X381890Y-135566D01*
X381187Y-135706D01*
X380592Y-136104D01*
X380361Y-136450D01*
X379836Y-136100D01*
X379284Y-135990D01*
X379394Y-135433D01*
X379255Y-134731D01*
X378857Y-134135D01*
X378261Y-133738D01*
X377559Y-133598D01*
D02*
G37*
G36*
X87254Y-137793D02*
X86552Y-137933D01*
X85957Y-138331D01*
X85559Y-138926D01*
X85419Y-139629D01*
X85559Y-140331D01*
X85957Y-140926D01*
X86552Y-141324D01*
X87254Y-141464D01*
X87957Y-141324D01*
X88060Y-141255D01*
X88269Y-141568D01*
X88865Y-141966D01*
X89567Y-142105D01*
X90269Y-141966D01*
X90865Y-141568D01*
X91263Y-140972D01*
X91402Y-140270D01*
X91263Y-139568D01*
X90865Y-138972D01*
X90269Y-138575D01*
X89567Y-138435D01*
X88865Y-138575D01*
X88761Y-138644D01*
X88552Y-138331D01*
X87957Y-137933D01*
X87254Y-137793D01*
D02*
G37*
G36*
X539900Y-138930D02*
X539198Y-139070D01*
X538602Y-139468D01*
X538205Y-140063D01*
X538065Y-140766D01*
X538205Y-141468D01*
X538602Y-142063D01*
X539198Y-142461D01*
X539900Y-142601D01*
X540602Y-142461D01*
X541198Y-142063D01*
X541596Y-141468D01*
X541736Y-140766D01*
X541596Y-140063D01*
X541198Y-139468D01*
X540602Y-139070D01*
X539900Y-138930D01*
D02*
G37*
G36*
X672401Y-128761D02*
X671048Y-128895D01*
X669747Y-129289D01*
X668549Y-129930D01*
X667498Y-130792D01*
X666636Y-131843D01*
X665995Y-133042D01*
X665601Y-134342D01*
X665467Y-135695D01*
X665601Y-137048D01*
X665995Y-138348D01*
X666636Y-139547D01*
X667498Y-140598D01*
X668549Y-141460D01*
X669747Y-142101D01*
X671048Y-142495D01*
X672401Y-142628D01*
X673753Y-142495D01*
X675054Y-142101D01*
X676253Y-141460D01*
X677303Y-140598D01*
X678166Y-139547D01*
X678806Y-138348D01*
X679201Y-137048D01*
X679334Y-135695D01*
X679201Y-134342D01*
X678806Y-133042D01*
X678166Y-131843D01*
X677303Y-130792D01*
X676253Y-129930D01*
X675054Y-129289D01*
X673753Y-128895D01*
X672401Y-128761D01*
D02*
G37*
G36*
X418898Y-142308D02*
X418195Y-142448D01*
X417863Y-142670D01*
X417531Y-142823D01*
X417107Y-142684D01*
X416808Y-142484D01*
X416106Y-142344D01*
X415403Y-142484D01*
X414808Y-142882D01*
X414410Y-143477D01*
X414270Y-144180D01*
X414410Y-144882D01*
X414808Y-145477D01*
X415403Y-145875D01*
X416106Y-146015D01*
X416808Y-145875D01*
X417140Y-145653D01*
X417472Y-145500D01*
X417896Y-145639D01*
X418195Y-145839D01*
X418898Y-145979D01*
X419600Y-145839D01*
X420195Y-145441D01*
X420593Y-144846D01*
X420733Y-144143D01*
X420593Y-143441D01*
X420195Y-142846D01*
X419600Y-142448D01*
X418898Y-142308D01*
D02*
G37*
G36*
X469291Y-142013D02*
X468589Y-142153D01*
X467994Y-142550D01*
X467596Y-143146D01*
X467456Y-143848D01*
X467596Y-144550D01*
X467994Y-145146D01*
X468589Y-145544D01*
X469291Y-145683D01*
X469994Y-145544D01*
X470589Y-145146D01*
X470987Y-144550D01*
X471127Y-143848D01*
X470987Y-143146D01*
X470589Y-142550D01*
X469994Y-142153D01*
X469291Y-142013D01*
D02*
G37*
G36*
X398568Y-143248D02*
X397866Y-143387D01*
X397270Y-143785D01*
X396873Y-144381D01*
X396733Y-145083D01*
X396873Y-145785D01*
X397270Y-146381D01*
X397866Y-146779D01*
X398568Y-146918D01*
X399271Y-146779D01*
X399866Y-146381D01*
X400264Y-145785D01*
X400403Y-145083D01*
X400264Y-144381D01*
X399866Y-143785D01*
X399271Y-143387D01*
X398568Y-143248D01*
D02*
G37*
G36*
X461319Y-141914D02*
X460617Y-142054D01*
X460021Y-142452D01*
X459623Y-143047D01*
X459484Y-143750D01*
X459623Y-144452D01*
X460021Y-145047D01*
X460617Y-145445D01*
X461319Y-145585D01*
X462021Y-145445D01*
X462341Y-145231D01*
X462701Y-145592D01*
X462633Y-145695D01*
X462493Y-146397D01*
X462633Y-147099D01*
X463031Y-147695D01*
X463626Y-148092D01*
X464328Y-148232D01*
X465031Y-148092D01*
X465626Y-147695D01*
X466024Y-147099D01*
X466164Y-146397D01*
X466024Y-145695D01*
X465626Y-145099D01*
X465031Y-144701D01*
X464328Y-144562D01*
X463626Y-144701D01*
X463306Y-144915D01*
X462946Y-144554D01*
X463015Y-144452D01*
X463154Y-143750D01*
X463015Y-143047D01*
X462617Y-142452D01*
X462021Y-142054D01*
X461319Y-141914D01*
D02*
G37*
G36*
X622001Y-137501D02*
X620744Y-137624D01*
X619535Y-137991D01*
X618421Y-138587D01*
X617444Y-139388D01*
X616643Y-140365D01*
X616047Y-141479D01*
X615680Y-142688D01*
X615556Y-143945D01*
X615680Y-145202D01*
X616047Y-146411D01*
X616643Y-147525D01*
X617444Y-148502D01*
X618421Y-149303D01*
X619535Y-149899D01*
X620744Y-150266D01*
X622001Y-150389D01*
X623258Y-150266D01*
X624467Y-149899D01*
X625581Y-149303D01*
X626558Y-148502D01*
X627359Y-147525D01*
X627955Y-146411D01*
X628321Y-145202D01*
X628445Y-143945D01*
X628321Y-142688D01*
X627955Y-141479D01*
X627359Y-140365D01*
X626558Y-139388D01*
X625581Y-138587D01*
X624467Y-137991D01*
X623258Y-137624D01*
X622001Y-137501D01*
D02*
G37*
G36*
X646457Y-154858D02*
X645754Y-154997D01*
X645159Y-155395D01*
X644761Y-155991D01*
X644743Y-156081D01*
X644233D01*
X644215Y-155991D01*
X643817Y-155395D01*
X643222Y-154997D01*
X642520Y-154858D01*
X641817Y-154997D01*
X641222Y-155395D01*
X640824Y-155991D01*
X640684Y-156693D01*
X640824Y-157395D01*
X641222Y-157991D01*
X641817Y-158388D01*
X642520Y-158528D01*
X642613Y-158510D01*
X642913Y-158960D01*
X642793Y-159140D01*
X642653Y-159843D01*
X642793Y-160545D01*
X643156Y-161088D01*
X643190Y-161201D01*
X643187Y-161739D01*
X642873Y-162208D01*
X642733Y-162910D01*
X642873Y-163613D01*
X643271Y-164208D01*
X643429Y-164314D01*
Y-164915D01*
X643321Y-164987D01*
X642923Y-165582D01*
X642784Y-166285D01*
X642923Y-166987D01*
X643321Y-167582D01*
X643917Y-167980D01*
X644619Y-168120D01*
X645321Y-167980D01*
X645917Y-167582D01*
X646315Y-166987D01*
X646454Y-166285D01*
X646315Y-165582D01*
X645917Y-164987D01*
X645759Y-164881D01*
Y-164280D01*
X645866Y-164208D01*
X646264Y-163613D01*
X646404Y-162910D01*
X646264Y-162208D01*
X645901Y-161665D01*
X645867Y-161552D01*
X645870Y-161014D01*
X646184Y-160545D01*
X646323Y-159843D01*
X646184Y-159140D01*
X646063Y-158960D01*
X646364Y-158510D01*
X646457Y-158528D01*
X647159Y-158388D01*
X647754Y-157991D01*
X648152Y-157395D01*
X648292Y-156693D01*
X648152Y-155991D01*
X647754Y-155395D01*
X647159Y-154997D01*
X646457Y-154858D01*
D02*
G37*
G36*
X162520Y-145659D02*
X161147Y-145794D01*
X159828Y-146195D01*
X158612Y-146844D01*
X157546Y-147719D01*
X156671Y-148785D01*
X156021Y-150001D01*
X155621Y-151321D01*
X155486Y-152693D01*
X155621Y-154065D01*
X156021Y-155385D01*
X156671Y-156601D01*
X157546Y-157667D01*
X158612Y-158541D01*
X159828Y-159191D01*
X161147Y-159592D01*
X162520Y-159727D01*
X163892Y-159592D01*
X165211Y-159191D01*
X166427Y-158541D01*
X167493Y-157667D01*
X168368Y-156601D01*
X169018Y-155385D01*
X169418Y-154065D01*
X169553Y-152693D01*
X169418Y-151321D01*
X169018Y-150001D01*
X168368Y-148785D01*
X167493Y-147719D01*
X166427Y-146844D01*
X165211Y-146195D01*
X163892Y-145794D01*
X162520Y-145659D01*
D02*
G37*
G36*
X518337Y-157799D02*
X517635Y-157938D01*
X517039Y-158336D01*
X516642Y-158932D01*
X516502Y-159634D01*
X516642Y-160336D01*
X516931Y-160769D01*
X517039Y-160932D01*
X516759Y-161344D01*
X516405Y-161107D01*
X515702Y-160968D01*
X515000Y-161107D01*
X514405Y-161505D01*
X514007Y-162100D01*
X513867Y-162803D01*
X514007Y-163505D01*
X514405Y-164100D01*
X515000Y-164498D01*
X515702Y-164638D01*
X516405Y-164498D01*
X517000Y-164100D01*
X517398Y-163505D01*
X517538Y-162803D01*
X517398Y-162100D01*
X517109Y-161668D01*
X517000Y-161505D01*
X517280Y-161092D01*
X517635Y-161329D01*
X518337Y-161469D01*
X519039Y-161329D01*
X519635Y-160932D01*
X520033Y-160336D01*
X520172Y-159634D01*
X520033Y-158932D01*
X519635Y-158336D01*
X519039Y-157938D01*
X518337Y-157799D01*
D02*
G37*
G36*
X406528Y-155931D02*
X405825Y-156071D01*
X405230Y-156469D01*
X404832Y-157064D01*
X404692Y-157767D01*
X404832Y-158469D01*
X405230Y-159064D01*
X405506Y-159249D01*
X405780Y-159723D01*
X405740Y-159955D01*
X405645Y-160433D01*
X405785Y-161135D01*
X406008Y-161470D01*
X405803Y-161921D01*
X405683Y-161981D01*
X405657Y-161975D01*
X405230Y-161690D01*
X404528Y-161551D01*
X403825Y-161690D01*
X403230Y-162088D01*
X402832Y-162683D01*
X402692Y-163386D01*
X402832Y-164088D01*
X403230Y-164683D01*
X403825Y-165081D01*
X404528Y-165221D01*
X405230Y-165081D01*
X405657Y-164796D01*
X406004Y-164722D01*
X406351Y-164796D01*
X406778Y-165081D01*
X407480Y-165221D01*
X408183Y-165081D01*
X408778Y-164683D01*
X409176Y-164088D01*
X409316Y-163386D01*
X409176Y-162683D01*
X408778Y-162088D01*
Y-161731D01*
X409176Y-161135D01*
X409316Y-160433D01*
X409176Y-159731D01*
X408778Y-159135D01*
X408502Y-158951D01*
X408228Y-158477D01*
X408268Y-158245D01*
X408363Y-157767D01*
X408223Y-157064D01*
X407825Y-156469D01*
X407230Y-156071D01*
X406528Y-155931D01*
D02*
G37*
G36*
X679921Y-158401D02*
X679219Y-158541D01*
X678623Y-158939D01*
X678226Y-159534D01*
X678086Y-160236D01*
X678226Y-160939D01*
X678623Y-161534D01*
X679219Y-161932D01*
X679921Y-162072D01*
X680624Y-161932D01*
X681219Y-161534D01*
X681617Y-160939D01*
X681756Y-160236D01*
X681617Y-159534D01*
X681219Y-158939D01*
X680624Y-158541D01*
X679921Y-158401D01*
D02*
G37*
G36*
X-3528Y-152395D02*
X-13402D01*
Y-162269D01*
X-3528D01*
Y-152395D01*
D02*
G37*
G36*
X470285Y-158353D02*
X469472Y-158514D01*
X468783Y-158975D01*
X468322Y-159664D01*
X468161Y-160477D01*
X468322Y-161289D01*
X468783Y-161978D01*
X469472Y-162439D01*
X470285Y-162600D01*
X471097Y-162439D01*
X471786Y-161978D01*
X472247Y-161289D01*
X472408Y-160477D01*
X472247Y-159664D01*
X471786Y-158975D01*
X471097Y-158514D01*
X470285Y-158353D01*
D02*
G37*
G36*
X391545D02*
X390732Y-158514D01*
X390043Y-158975D01*
X389582Y-159664D01*
X389421Y-160477D01*
X389582Y-161289D01*
X390043Y-161978D01*
X390732Y-162439D01*
X391545Y-162600D01*
X392357Y-162439D01*
X393046Y-161978D01*
X393507Y-161289D01*
X393668Y-160477D01*
X393507Y-159664D01*
X393046Y-158975D01*
X392357Y-158514D01*
X391545Y-158353D01*
D02*
G37*
G36*
X533015Y-148825D02*
X531662Y-148958D01*
X530360Y-149353D01*
X529160Y-149995D01*
X528109Y-150857D01*
X527246Y-151909D01*
X526605Y-153109D01*
X526210Y-154410D01*
X526076Y-155764D01*
X526210Y-157118D01*
X526605Y-158419D01*
X527246Y-159619D01*
X528109Y-160671D01*
X529160Y-161533D01*
X530360Y-162175D01*
X531662Y-162570D01*
X533015Y-162703D01*
X534369Y-162570D01*
X535671Y-162175D01*
X536870Y-161533D01*
X537922Y-160671D01*
X538785Y-159619D01*
X539426Y-158419D01*
X539821Y-157118D01*
X539954Y-155764D01*
X539821Y-154410D01*
X539426Y-153109D01*
X538785Y-151909D01*
X537922Y-150857D01*
X536870Y-149995D01*
X535671Y-149353D01*
X534369Y-148958D01*
X533015Y-148825D01*
D02*
G37*
G36*
X336415D02*
X335062Y-148958D01*
X333760Y-149353D01*
X332560Y-149995D01*
X331509Y-150857D01*
X330646Y-151909D01*
X330005Y-153109D01*
X329610Y-154410D01*
X329476Y-155764D01*
X329610Y-157118D01*
X330005Y-158419D01*
X330646Y-159619D01*
X331509Y-160671D01*
X332560Y-161533D01*
X333760Y-162175D01*
X335062Y-162570D01*
X336415Y-162703D01*
X337769Y-162570D01*
X339071Y-162175D01*
X340270Y-161533D01*
X341322Y-160671D01*
X342185Y-159619D01*
X342826Y-158419D01*
X343221Y-157118D01*
X343354Y-155764D01*
X343221Y-154410D01*
X342826Y-153109D01*
X342185Y-151909D01*
X341322Y-150857D01*
X340270Y-149995D01*
X339071Y-149353D01*
X337769Y-148958D01*
X336415Y-148825D01*
D02*
G37*
G36*
X302362Y-150664D02*
X301186Y-150780D01*
X300055Y-151123D01*
X299013Y-151680D01*
X298099Y-152430D01*
X297349Y-153343D01*
X296792Y-154386D01*
X296449Y-155517D01*
X296333Y-156693D01*
X296449Y-157869D01*
X296792Y-159000D01*
X297349Y-160043D01*
X298099Y-160956D01*
X299013Y-161706D01*
X300055Y-162263D01*
X301186Y-162606D01*
X302362Y-162722D01*
X303538Y-162606D01*
X304669Y-162263D01*
X305712Y-161706D01*
X306625Y-160956D01*
X307375Y-160043D01*
X307932Y-159000D01*
X308275Y-157869D01*
X308391Y-156693D01*
X308275Y-155517D01*
X307932Y-154386D01*
X307375Y-153343D01*
X306625Y-152430D01*
X305712Y-151680D01*
X304669Y-151123D01*
X303538Y-150780D01*
X302362Y-150664D01*
D02*
G37*
G36*
X142520D02*
X141343Y-150780D01*
X140213Y-151123D01*
X139170Y-151680D01*
X138257Y-152430D01*
X137507Y-153343D01*
X136950Y-154386D01*
X136607Y-155517D01*
X136491Y-156693D01*
X136607Y-157869D01*
X136950Y-159000D01*
X137507Y-160043D01*
X138257Y-160956D01*
X139170Y-161706D01*
X140213Y-162263D01*
X141343Y-162606D01*
X142520Y-162722D01*
X143696Y-162606D01*
X144827Y-162263D01*
X145869Y-161706D01*
X146783Y-160956D01*
X147533Y-160043D01*
X148090Y-159000D01*
X148433Y-157869D01*
X148549Y-156693D01*
X148433Y-155517D01*
X148090Y-154386D01*
X147533Y-153343D01*
X146783Y-152430D01*
X145869Y-151680D01*
X144827Y-151123D01*
X143696Y-150780D01*
X142520Y-150664D01*
D02*
G37*
G36*
X684646Y-159976D02*
X683943Y-160116D01*
X683348Y-160513D01*
X682950Y-161109D01*
X682810Y-161811D01*
X682950Y-162513D01*
X683348Y-163109D01*
X683943Y-163507D01*
X684646Y-163646D01*
X685348Y-163507D01*
X685943Y-163109D01*
X686341Y-162513D01*
X686481Y-161811D01*
X686341Y-161109D01*
X685943Y-160513D01*
X685348Y-160116D01*
X684646Y-159976D01*
D02*
G37*
G36*
X89567Y-164535D02*
X88865Y-164674D01*
X88362Y-165010D01*
X87870Y-164681D01*
X87167Y-164542D01*
X86465Y-164681D01*
X85869Y-165079D01*
X85472Y-165675D01*
X85332Y-166377D01*
X85472Y-167079D01*
X85814Y-167592D01*
X85264Y-167959D01*
X84867Y-168555D01*
X84727Y-169257D01*
X84867Y-169959D01*
X85264Y-170555D01*
X85860Y-170952D01*
X86562Y-171092D01*
X87265Y-170952D01*
X87860Y-170555D01*
X88258Y-169959D01*
X88398Y-169257D01*
X88258Y-168555D01*
X87915Y-168042D01*
X88372Y-167737D01*
X88865Y-168066D01*
X89567Y-168205D01*
X90270Y-168066D01*
X90865Y-167668D01*
X91263Y-167072D01*
X91403Y-166370D01*
X91263Y-165668D01*
X90865Y-165072D01*
X90270Y-164674D01*
X89567Y-164535D01*
D02*
G37*
G36*
X689370Y-159582D02*
X688668Y-159722D01*
X688072Y-160120D01*
X687675Y-160715D01*
X687535Y-161417D01*
X687675Y-162120D01*
X688072Y-162715D01*
X688234Y-162823D01*
X688466Y-163269D01*
X688344Y-163452D01*
X688068Y-163865D01*
X687928Y-164567D01*
X688068Y-165269D01*
X688466Y-165865D01*
X688725Y-166038D01*
Y-166639D01*
X688466Y-166813D01*
X688068Y-167408D01*
X687928Y-168110D01*
X688068Y-168813D01*
X688466Y-169408D01*
X689061Y-169806D01*
X689764Y-169946D01*
X690466Y-169806D01*
X691061Y-169408D01*
X691459Y-168813D01*
X691599Y-168110D01*
X691459Y-167408D01*
X691061Y-166813D01*
X690802Y-166639D01*
Y-166038D01*
X691061Y-165865D01*
X691459Y-165269D01*
X691599Y-164567D01*
X691459Y-163865D01*
X691061Y-163269D01*
X690900Y-163161D01*
X690668Y-162715D01*
X690790Y-162532D01*
X691066Y-162120D01*
X691205Y-161417D01*
X691066Y-160715D01*
X690668Y-160120D01*
X690072Y-159722D01*
X689370Y-159582D01*
D02*
G37*
G36*
X284862Y-157759D02*
X283490Y-157894D01*
X282171Y-158294D01*
X280954Y-158944D01*
X279889Y-159819D01*
X279014Y-160885D01*
X278364Y-162101D01*
X277963Y-163421D01*
X277828Y-164793D01*
X277963Y-166165D01*
X278364Y-167485D01*
X279014Y-168701D01*
X279889Y-169767D01*
X280954Y-170641D01*
X282171Y-171291D01*
X283490Y-171692D01*
X284862Y-171827D01*
X286234Y-171692D01*
X287554Y-171291D01*
X288770Y-170641D01*
X289836Y-169767D01*
X290711Y-168701D01*
X291361Y-167485D01*
X291761Y-166165D01*
X291896Y-164793D01*
X291761Y-163421D01*
X291361Y-162101D01*
X290711Y-160885D01*
X289836Y-159819D01*
X288770Y-158944D01*
X287554Y-158294D01*
X286234Y-157894D01*
X284862Y-157759D01*
D02*
G37*
G36*
X30512Y-168440D02*
X29809Y-168580D01*
X29214Y-168978D01*
X28816Y-169573D01*
X28677Y-170276D01*
X28816Y-170978D01*
X29214Y-171573D01*
X29809Y-171971D01*
X30512Y-172111D01*
X31214Y-171971D01*
X31809Y-171573D01*
X32207Y-170978D01*
X32347Y-170276D01*
X32207Y-169573D01*
X31809Y-168978D01*
X31214Y-168580D01*
X30512Y-168440D01*
D02*
G37*
G36*
X644488Y-168637D02*
X643786Y-168777D01*
X643190Y-169175D01*
X642793Y-169770D01*
X642653Y-170472D01*
X642793Y-171175D01*
X643190Y-171770D01*
X643786Y-172168D01*
X644488Y-172308D01*
X645190Y-172168D01*
X645786Y-171770D01*
X646184Y-171175D01*
X646323Y-170472D01*
X646184Y-169770D01*
X645786Y-169175D01*
X645190Y-168777D01*
X644488Y-168637D01*
D02*
G37*
G36*
X413440Y-173015D02*
X412737Y-173154D01*
X412148Y-173548D01*
X411745Y-173278D01*
X411043Y-173139D01*
X410340Y-173278D01*
X409745Y-173676D01*
X409347Y-174272D01*
X409207Y-174974D01*
X409347Y-175676D01*
X409745Y-176272D01*
X410340Y-176670D01*
X411043Y-176809D01*
X411745Y-176670D01*
X412334Y-176276D01*
X412737Y-176546D01*
X413440Y-176685D01*
X414142Y-176546D01*
X414737Y-176148D01*
X415135Y-175552D01*
X415275Y-174850D01*
X415135Y-174148D01*
X414737Y-173552D01*
X414142Y-173154D01*
X413440Y-173015D01*
D02*
G37*
G36*
X404823Y-173509D02*
X404120Y-173649D01*
X403543Y-174034D01*
X402966Y-173649D01*
X402264Y-173509D01*
X401561Y-173649D01*
X400966Y-174046D01*
X400568Y-174642D01*
X400428Y-175344D01*
X400568Y-176046D01*
X400966Y-176642D01*
X401561Y-177040D01*
X402264Y-177179D01*
X402966Y-177040D01*
X403543Y-176654D01*
X404120Y-177040D01*
X404823Y-177179D01*
X405525Y-177040D01*
X406121Y-176642D01*
X406518Y-176046D01*
X406658Y-175344D01*
X406518Y-174642D01*
X406121Y-174046D01*
X405525Y-173649D01*
X404823Y-173509D01*
D02*
G37*
G36*
X437697Y-173410D02*
X436995Y-173550D01*
X436399Y-173948D01*
X436049Y-174471D01*
X435778Y-174511D01*
X435506Y-174471D01*
X435156Y-173948D01*
X434561Y-173550D01*
X433858Y-173410D01*
X433156Y-173550D01*
X432561Y-173948D01*
X431959Y-173949D01*
X431509Y-173649D01*
X430807Y-173509D01*
X430105Y-173649D01*
X429509Y-174046D01*
X429297Y-174364D01*
X429295Y-174365D01*
X428718Y-174330D01*
X428463Y-173948D01*
X427868Y-173550D01*
X427165Y-173410D01*
X426463Y-173550D01*
X425868Y-173948D01*
X425470Y-174543D01*
X425330Y-175246D01*
X425470Y-175948D01*
X425868Y-176543D01*
X426463Y-176941D01*
X427165Y-177081D01*
X427868Y-176941D01*
X428463Y-176543D01*
X428676Y-176225D01*
X428677Y-176225D01*
X429254Y-176260D01*
X429509Y-176642D01*
X430105Y-177040D01*
X430807Y-177179D01*
X431509Y-177040D01*
X432105Y-176642D01*
X432707Y-176641D01*
X433156Y-176941D01*
X433858Y-177081D01*
X434561Y-176941D01*
X435156Y-176543D01*
X435506Y-176020D01*
X435778Y-175980D01*
X436049Y-176020D01*
X436399Y-176543D01*
X436995Y-176941D01*
X437697Y-177081D01*
X438399Y-176941D01*
X438995Y-176543D01*
X439392Y-175948D01*
X439532Y-175246D01*
X439392Y-174543D01*
X438995Y-173948D01*
X438399Y-173550D01*
X437697Y-173410D01*
D02*
G37*
G36*
X421596Y-173198D02*
X420894Y-173338D01*
X420298Y-173736D01*
X419901Y-174331D01*
X419835Y-174662D01*
X419325D01*
X419292Y-174495D01*
X418894Y-173899D01*
X418299Y-173501D01*
X417596Y-173362D01*
X416894Y-173501D01*
X416298Y-173899D01*
X415901Y-174495D01*
X415761Y-175197D01*
X415901Y-175899D01*
X416298Y-176495D01*
X416894Y-176892D01*
X417596Y-177032D01*
X418299Y-176892D01*
X418894Y-176495D01*
X419292Y-175899D01*
X419358Y-175568D01*
X419867D01*
X419901Y-175736D01*
X420298Y-176331D01*
X420894Y-176729D01*
X421596Y-176869D01*
X422299Y-176729D01*
X422894Y-176331D01*
X423292Y-175736D01*
X423431Y-175034D01*
X423292Y-174331D01*
X422894Y-173736D01*
X422299Y-173338D01*
X421596Y-173198D01*
D02*
G37*
G36*
X530027Y-171152D02*
X529325Y-171292D01*
X528729Y-171690D01*
X528332Y-172285D01*
X528192Y-172987D01*
X528332Y-173690D01*
X528729Y-174285D01*
X529325Y-174683D01*
X530027Y-174823D01*
X530729Y-174683D01*
X531325Y-174285D01*
X531723Y-173690D01*
X531862Y-172987D01*
X531723Y-172285D01*
X531325Y-171690D01*
X530729Y-171292D01*
X530027Y-171152D01*
D02*
G37*
G36*
X476945Y-171393D02*
X476243Y-171533D01*
X475647Y-171931D01*
X475250Y-172526D01*
X475110Y-173228D01*
X475250Y-173931D01*
X475647Y-174526D01*
X476243Y-174924D01*
X476945Y-175064D01*
X477648Y-174924D01*
X478243Y-174526D01*
X478641Y-173931D01*
X478781Y-173228D01*
X478641Y-172526D01*
X478243Y-171931D01*
X477648Y-171533D01*
X476945Y-171393D01*
D02*
G37*
G36*
X450850Y-172292D02*
X450147Y-172431D01*
X449552Y-172829D01*
X449154Y-173424D01*
X449014Y-174127D01*
X449154Y-174829D01*
X449552Y-175425D01*
X450147Y-175822D01*
X450850Y-175962D01*
X451552Y-175822D01*
X452147Y-175425D01*
X452545Y-174829D01*
X452685Y-174127D01*
X452545Y-173424D01*
X452147Y-172829D01*
X451552Y-172431D01*
X450850Y-172292D01*
D02*
G37*
G36*
X443898Y-173214D02*
X443195Y-173353D01*
X442600Y-173751D01*
X442202Y-174346D01*
X442062Y-175049D01*
X442202Y-175751D01*
X442600Y-176347D01*
X443195Y-176744D01*
X443898Y-176884D01*
X444600Y-176744D01*
X445195Y-176347D01*
X445593Y-175751D01*
X445733Y-175049D01*
X445593Y-174346D01*
X445195Y-173751D01*
X444600Y-173353D01*
X443898Y-173214D01*
D02*
G37*
G36*
X469390Y-173312D02*
X468687Y-173452D01*
X468092Y-173849D01*
X467694Y-174445D01*
X467555Y-175147D01*
X467694Y-175850D01*
X468092Y-176445D01*
X468687Y-176843D01*
X469390Y-176982D01*
X470092Y-176843D01*
X470687Y-176445D01*
X471085Y-175850D01*
X471225Y-175147D01*
X471085Y-174445D01*
X470687Y-173849D01*
X470092Y-173452D01*
X469390Y-173312D01*
D02*
G37*
G36*
X86614Y-173362D02*
X85912Y-173501D01*
X85316Y-173899D01*
X84919Y-174495D01*
X84779Y-175197D01*
X84919Y-175899D01*
X85316Y-176495D01*
X85912Y-176892D01*
X86614Y-177032D01*
X87317Y-176892D01*
X87912Y-176495D01*
X88310Y-175899D01*
X88449Y-175197D01*
X88310Y-174495D01*
X87912Y-173899D01*
X87317Y-173501D01*
X86614Y-173362D01*
D02*
G37*
G36*
X457283Y-173312D02*
X456581Y-173452D01*
X455986Y-173849D01*
X455588Y-174445D01*
X455448Y-175147D01*
X455588Y-175850D01*
X455986Y-176445D01*
X456581Y-176843D01*
X457283Y-176982D01*
X457986Y-176843D01*
X458581Y-176445D01*
X458870Y-176717D01*
X458888Y-176745D01*
X459484Y-177143D01*
X460186Y-177283D01*
X460888Y-177143D01*
X461484Y-176745D01*
X461881Y-176150D01*
X462021Y-175448D01*
X461881Y-174745D01*
X461484Y-174150D01*
X460888Y-173752D01*
X460186Y-173612D01*
X459484Y-173752D01*
X458888Y-174150D01*
X458782D01*
X458581Y-173849D01*
X457986Y-173452D01*
X457283Y-173312D01*
D02*
G37*
G36*
X533044Y-174390D02*
X532342Y-174530D01*
X531746Y-174927D01*
X531348Y-175523D01*
X531209Y-176225D01*
X531348Y-176927D01*
X531746Y-177523D01*
X532342Y-177921D01*
X533044Y-178060D01*
X533746Y-177921D01*
X534342Y-177523D01*
X534739Y-176927D01*
X534879Y-176225D01*
X534739Y-175523D01*
X534342Y-174927D01*
X533746Y-174530D01*
X533044Y-174390D01*
D02*
G37*
G36*
X474016Y-174543D02*
X473313Y-174682D01*
X472718Y-175080D01*
X472320Y-175676D01*
X472181Y-176378D01*
X472320Y-177080D01*
X472718Y-177676D01*
X473313Y-178074D01*
X474016Y-178213D01*
X474718Y-178074D01*
X475314Y-177676D01*
X475711Y-177080D01*
X475851Y-176378D01*
X475711Y-175676D01*
X475314Y-175080D01*
X474718Y-174682D01*
X474016Y-174543D01*
D02*
G37*
G36*
X423461Y-177034D02*
X422758Y-177173D01*
X422163Y-177571D01*
X421765Y-178167D01*
X421626Y-178869D01*
X421765Y-179571D01*
X422163Y-180167D01*
X422758Y-180565D01*
X423461Y-180704D01*
X424163Y-180565D01*
X424758Y-180167D01*
X425156Y-179571D01*
X425296Y-178869D01*
X425156Y-178167D01*
X424758Y-177571D01*
X424163Y-177173D01*
X423461Y-177034D01*
D02*
G37*
G36*
X74803Y-177299D02*
X74101Y-177438D01*
X73505Y-177836D01*
X73108Y-178431D01*
X72968Y-179134D01*
X73108Y-179836D01*
X73505Y-180432D01*
X74101Y-180829D01*
X74803Y-180969D01*
X75506Y-180829D01*
X76101Y-180432D01*
X76499Y-179836D01*
X76638Y-179134D01*
X76499Y-178431D01*
X76101Y-177836D01*
X75506Y-177438D01*
X74803Y-177299D01*
D02*
G37*
G36*
X63976D02*
X63274Y-177438D01*
X62679Y-177836D01*
X62281Y-178431D01*
X62141Y-179134D01*
X62281Y-179836D01*
X62679Y-180432D01*
X63274Y-180829D01*
X63976Y-180969D01*
X64679Y-180829D01*
X65274Y-180432D01*
X65672Y-179836D01*
X65812Y-179134D01*
X65672Y-178431D01*
X65274Y-177836D01*
X64679Y-177438D01*
X63976Y-177299D01*
D02*
G37*
G36*
X499111Y-177693D02*
X498408Y-177833D01*
X497813Y-178231D01*
X497415Y-178826D01*
X497275Y-179528D01*
X497415Y-180231D01*
X497813Y-180826D01*
X498408Y-181224D01*
X499111Y-181363D01*
X499813Y-181224D01*
X500408Y-180826D01*
X500806Y-180231D01*
X500946Y-179528D01*
X500806Y-178826D01*
X500408Y-178231D01*
X499813Y-177833D01*
X499111Y-177693D01*
D02*
G37*
G36*
X80709Y-178283D02*
X80006Y-178423D01*
X79411Y-178820D01*
X79013Y-179416D01*
X78873Y-180118D01*
X79013Y-180820D01*
X79411Y-181416D01*
X80006Y-181814D01*
X80709Y-181953D01*
X81411Y-181814D01*
X82006Y-181416D01*
X82404Y-180820D01*
X82544Y-180118D01*
X82404Y-179416D01*
X82006Y-178820D01*
X81411Y-178423D01*
X80709Y-178283D01*
D02*
G37*
G36*
X498819Y-182023D02*
X498117Y-182163D01*
X497521Y-182561D01*
X497123Y-183156D01*
X496984Y-183858D01*
X497123Y-184561D01*
X497521Y-185156D01*
X498117Y-185554D01*
X498819Y-185694D01*
X499521Y-185554D01*
X500117Y-185156D01*
X500515Y-184561D01*
X500654Y-183858D01*
X500515Y-183156D01*
X500117Y-182561D01*
X499521Y-182163D01*
X498819Y-182023D01*
D02*
G37*
G36*
X-23622Y-175330D02*
X-24324Y-175470D01*
X-24920Y-175868D01*
X-25318Y-176463D01*
X-25457Y-177165D01*
X-25318Y-177868D01*
X-24920Y-178463D01*
X-24324Y-178861D01*
X-24234Y-178879D01*
Y-179389D01*
X-24324Y-179407D01*
X-24920Y-179805D01*
X-25318Y-180400D01*
X-25457Y-181102D01*
X-25318Y-181805D01*
X-25032Y-182231D01*
X-24958Y-182579D01*
X-25032Y-182926D01*
X-25318Y-183353D01*
X-25457Y-184055D01*
X-25318Y-184757D01*
X-24920Y-185353D01*
X-24324Y-185751D01*
X-24234Y-185769D01*
Y-186278D01*
X-24324Y-186297D01*
X-24920Y-186694D01*
X-25318Y-187290D01*
X-25457Y-187992D01*
X-25318Y-188695D01*
X-24920Y-189290D01*
X-24324Y-189688D01*
X-23622Y-189827D01*
X-22920Y-189688D01*
X-22324Y-189290D01*
X-21926Y-188695D01*
X-21787Y-187992D01*
X-21926Y-187290D01*
X-22324Y-186694D01*
X-22920Y-186297D01*
X-23010Y-186278D01*
Y-185769D01*
X-22920Y-185751D01*
X-22324Y-185353D01*
X-21926Y-184757D01*
X-21787Y-184055D01*
X-21926Y-183353D01*
X-22212Y-182926D01*
X-22286Y-182579D01*
X-22212Y-182231D01*
X-21926Y-181805D01*
X-21787Y-181102D01*
X-21926Y-180400D01*
X-22324Y-179805D01*
X-22920Y-179407D01*
X-23010Y-179389D01*
Y-178879D01*
X-22920Y-178861D01*
X-22324Y-178463D01*
X-21926Y-177868D01*
X-21787Y-177165D01*
X-21926Y-176463D01*
X-22324Y-175868D01*
X-22920Y-175470D01*
X-23622Y-175330D01*
D02*
G37*
G36*
X498693Y-186515D02*
X497991Y-186655D01*
X497395Y-187053D01*
X496997Y-187648D01*
X496858Y-188351D01*
X496997Y-189053D01*
X497395Y-189648D01*
X497991Y-190046D01*
X498693Y-190186D01*
X499395Y-190046D01*
X499991Y-189648D01*
X500388Y-189053D01*
X500528Y-188351D01*
X500388Y-187648D01*
X499991Y-187053D01*
X499395Y-186655D01*
X498693Y-186515D01*
D02*
G37*
G36*
X549298Y-190153D02*
X548596Y-190292D01*
X548001Y-190690D01*
X547603Y-191286D01*
X547463Y-191988D01*
X547603Y-192690D01*
X548001Y-193286D01*
X548596Y-193683D01*
X549298Y-193823D01*
X550001Y-193683D01*
X550596Y-193286D01*
X550994Y-192690D01*
X551134Y-191988D01*
X550994Y-191286D01*
X550596Y-190690D01*
X550001Y-190292D01*
X549298Y-190153D01*
D02*
G37*
G36*
X569291Y-192259D02*
X568589Y-192399D01*
X567994Y-192797D01*
X567596Y-193392D01*
X567456Y-194095D01*
X567596Y-194797D01*
X567994Y-195392D01*
X568589Y-195790D01*
X569291Y-195930D01*
X569994Y-195790D01*
X570589Y-195392D01*
X570987Y-194797D01*
X571127Y-194095D01*
X570987Y-193392D01*
X570589Y-192797D01*
X569994Y-192399D01*
X569291Y-192259D01*
D02*
G37*
G36*
X358661Y-192653D02*
X357959Y-192793D01*
X357364Y-193191D01*
X356966Y-193786D01*
X356826Y-194488D01*
X356966Y-195191D01*
X357364Y-195786D01*
X357959Y-196184D01*
X358661Y-196324D01*
X359364Y-196184D01*
X359959Y-195786D01*
X360357Y-195191D01*
X360497Y-194488D01*
X360357Y-193786D01*
X359959Y-193191D01*
X359364Y-192793D01*
X358661Y-192653D01*
D02*
G37*
G36*
X340904Y-192546D02*
X340092Y-192708D01*
X339403Y-193168D01*
X338942Y-193857D01*
X338780Y-194670D01*
X338942Y-195483D01*
X339403Y-196172D01*
X340092Y-196632D01*
X340904Y-196794D01*
X341717Y-196632D01*
X342406Y-196172D01*
X342866Y-195483D01*
X343028Y-194670D01*
X342866Y-193857D01*
X342406Y-193168D01*
X341717Y-192708D01*
X340904Y-192546D01*
D02*
G37*
G36*
X528395Y-192556D02*
X527583Y-192718D01*
X526894Y-193178D01*
X526433Y-193867D01*
X526271Y-194680D01*
X526433Y-195492D01*
X526894Y-196181D01*
X527583Y-196642D01*
X528395Y-196804D01*
X529208Y-196642D01*
X529897Y-196181D01*
X530358Y-195492D01*
X530519Y-194680D01*
X530358Y-193867D01*
X529897Y-193178D01*
X529208Y-192718D01*
X528395Y-192556D01*
D02*
G37*
G36*
X598425Y-196984D02*
X597723Y-197123D01*
X597127Y-197521D01*
X597100Y-197562D01*
X596600D01*
X596573Y-197521D01*
X595978Y-197123D01*
X595276Y-196984D01*
X594573Y-197123D01*
X593978Y-197521D01*
X593951Y-197562D01*
X593451D01*
X593424Y-197521D01*
X592828Y-197123D01*
X592126Y-196984D01*
X591424Y-197123D01*
X590945Y-197443D01*
X590466Y-197123D01*
X589764Y-196984D01*
X589061Y-197123D01*
X588771Y-197318D01*
X588386Y-197486D01*
X588001Y-197318D01*
X587710Y-197123D01*
X587008Y-196984D01*
X586306Y-197123D01*
X585710Y-197521D01*
X585312Y-198117D01*
X585173Y-198819D01*
X585312Y-199521D01*
X585710Y-200117D01*
X586306Y-200515D01*
X587008Y-200654D01*
X587710Y-200515D01*
X588001Y-200320D01*
X588386Y-200152D01*
X588771Y-200320D01*
X589061Y-200515D01*
X589764Y-200654D01*
X590466Y-200515D01*
X590945Y-200195D01*
X591424Y-200515D01*
X592126Y-200654D01*
X592828Y-200515D01*
X593424Y-200117D01*
X593451Y-200076D01*
X593951D01*
X593978Y-200117D01*
X594573Y-200515D01*
X595276Y-200654D01*
X595978Y-200515D01*
X596573Y-200117D01*
X596600Y-200076D01*
X597100D01*
X597127Y-200117D01*
X597723Y-200515D01*
X598425Y-200654D01*
X599127Y-200515D01*
X599723Y-200117D01*
X600121Y-199521D01*
X600260Y-198819D01*
X600121Y-198117D01*
X599723Y-197521D01*
X599127Y-197123D01*
X598425Y-196984D01*
D02*
G37*
G36*
X416835Y-194746D02*
X416132Y-194885D01*
X415537Y-195283D01*
X415139Y-195879D01*
X414999Y-196581D01*
X415139Y-197283D01*
X415537Y-197879D01*
X416132Y-198276D01*
X416835Y-198416D01*
X417537Y-198276D01*
X418132Y-197879D01*
X418530Y-197283D01*
X418670Y-196581D01*
X418530Y-195879D01*
X418132Y-195283D01*
X417537Y-194885D01*
X416835Y-194746D01*
D02*
G37*
G36*
X411811Y-195015D02*
X411109Y-195155D01*
X410513Y-195553D01*
X410115Y-196148D01*
X409976Y-196850D01*
X410115Y-197553D01*
X410513Y-198148D01*
X411109Y-198546D01*
X411811Y-198686D01*
X412513Y-198546D01*
X413109Y-198148D01*
X413507Y-197553D01*
X413646Y-196850D01*
X413507Y-196148D01*
X413109Y-195553D01*
X412513Y-195155D01*
X411811Y-195015D01*
D02*
G37*
G36*
X326966Y-193336D02*
X326264Y-193476D01*
X325669Y-193873D01*
X325271Y-194469D01*
X325131Y-195171D01*
X325271Y-195873D01*
X325605Y-196374D01*
X325273Y-196871D01*
X325133Y-197573D01*
X325273Y-198275D01*
X325671Y-198871D01*
X326266Y-199269D01*
X326969Y-199408D01*
X327671Y-199269D01*
X328266Y-198871D01*
X328664Y-198275D01*
X328804Y-197573D01*
X328664Y-196871D01*
X328330Y-196371D01*
X328662Y-195873D01*
X328802Y-195171D01*
X328662Y-194469D01*
X328264Y-193873D01*
X327669Y-193476D01*
X326966Y-193336D01*
D02*
G37*
G36*
X581496Y-196984D02*
X580794Y-197123D01*
X580198Y-197521D01*
X579801Y-198117D01*
X579661Y-198819D01*
X579801Y-199521D01*
X580198Y-200117D01*
X580794Y-200515D01*
X581496Y-200654D01*
X582198Y-200515D01*
X582794Y-200117D01*
X583192Y-199521D01*
X583331Y-198819D01*
X583192Y-198117D01*
X582794Y-197521D01*
X582198Y-197123D01*
X581496Y-196984D01*
D02*
G37*
G36*
X573622D02*
X572920Y-197123D01*
X572324Y-197521D01*
X571926Y-198117D01*
X571787Y-198819D01*
X571926Y-199521D01*
X572324Y-200117D01*
X572920Y-200515D01*
X573622Y-200654D01*
X574324Y-200515D01*
X574920Y-200117D01*
X575318Y-199521D01*
X575457Y-198819D01*
X575318Y-198117D01*
X574920Y-197521D01*
X574324Y-197123D01*
X573622Y-196984D01*
D02*
G37*
G36*
X675591Y-194621D02*
X674888Y-194761D01*
X674293Y-195159D01*
X673895Y-195754D01*
X673755Y-196457D01*
X673895Y-197159D01*
X674293Y-197754D01*
X674390Y-197819D01*
X674417Y-197945D01*
X674355Y-198398D01*
X673899Y-198702D01*
X673501Y-199298D01*
X673362Y-200000D01*
X673501Y-200702D01*
X673899Y-201298D01*
X674495Y-201696D01*
X675197Y-201835D01*
X675899Y-201696D01*
X676495Y-201298D01*
X676668Y-201038D01*
X677269D01*
X677442Y-201298D01*
X678038Y-201696D01*
X678740Y-201835D01*
X679443Y-201696D01*
X680005Y-201320D01*
X680152Y-201257D01*
X680478D01*
X680625Y-201320D01*
X681187Y-201696D01*
X681890Y-201835D01*
X682592Y-201696D01*
X683187Y-201298D01*
X683585Y-200702D01*
X683725Y-200000D01*
X683585Y-199298D01*
X683209Y-198735D01*
X683147Y-198588D01*
Y-198262D01*
X683209Y-198116D01*
X683585Y-197553D01*
X683725Y-196850D01*
X683585Y-196148D01*
X683187Y-195553D01*
X682592Y-195155D01*
X681890Y-195015D01*
X681187Y-195155D01*
X680625Y-195531D01*
X680478Y-195593D01*
X680152D01*
X680005Y-195531D01*
X679443Y-195155D01*
X678740Y-195015D01*
X678038Y-195155D01*
X677625Y-195431D01*
X677442Y-195553D01*
X676996Y-195320D01*
X676888Y-195159D01*
X676293Y-194761D01*
X675591Y-194621D01*
D02*
G37*
G36*
X372016Y-198952D02*
X371313Y-199092D01*
X370718Y-199490D01*
X370320Y-200085D01*
X370181Y-200787D01*
X370320Y-201490D01*
X370718Y-202085D01*
X371313Y-202483D01*
X372016Y-202623D01*
X372718Y-202483D01*
X373313Y-202085D01*
X373711Y-201490D01*
X373851Y-200787D01*
X373711Y-200085D01*
X373313Y-199490D01*
X372718Y-199092D01*
X372016Y-198952D01*
D02*
G37*
G36*
X509842Y-193883D02*
X509140Y-194023D01*
X508545Y-194420D01*
X508147Y-195016D01*
X508007Y-195718D01*
X508147Y-196420D01*
X508335Y-196702D01*
X508147Y-196984D01*
X508007Y-197687D01*
X508147Y-198389D01*
X508335Y-198671D01*
X508147Y-198953D01*
X508007Y-199655D01*
X508147Y-200357D01*
X508335Y-200639D01*
X508147Y-200921D01*
X508007Y-201624D01*
X508147Y-202326D01*
X508545Y-202921D01*
X509140Y-203319D01*
X509842Y-203459D01*
X510545Y-203319D01*
X511140Y-202921D01*
X511538Y-202326D01*
X511678Y-201624D01*
X511538Y-200921D01*
X511350Y-200639D01*
X511538Y-200357D01*
X511678Y-199655D01*
X511538Y-198953D01*
X511350Y-198671D01*
X511538Y-198389D01*
X511678Y-197687D01*
X511538Y-196984D01*
X511350Y-196702D01*
X511538Y-196420D01*
X511678Y-195718D01*
X511538Y-195016D01*
X511140Y-194420D01*
X510545Y-194023D01*
X509842Y-193883D01*
D02*
G37*
G36*
X366535Y-200527D02*
X365833Y-200667D01*
X365238Y-201064D01*
X364840Y-201660D01*
X364700Y-202362D01*
X364840Y-203064D01*
X365238Y-203660D01*
X365833Y-204058D01*
X366535Y-204198D01*
X367238Y-204058D01*
X367833Y-203660D01*
X368231Y-203064D01*
X368371Y-202362D01*
X368231Y-201660D01*
X367833Y-201064D01*
X367238Y-200667D01*
X366535Y-200527D01*
D02*
G37*
G36*
X544291Y-193883D02*
X543589Y-194023D01*
X542994Y-194420D01*
X542596Y-195016D01*
X542456Y-195718D01*
X542596Y-196420D01*
X542784Y-196702D01*
X542596Y-196984D01*
X542456Y-197687D01*
X542596Y-198389D01*
X542784Y-198671D01*
X542596Y-198953D01*
X542456Y-199655D01*
X542596Y-200357D01*
X542784Y-200639D01*
X542596Y-200921D01*
X542456Y-201624D01*
X542596Y-202326D01*
X542994Y-202921D01*
X543589Y-203319D01*
X544291Y-203459D01*
X544994Y-203319D01*
X545496Y-203585D01*
X545548Y-203852D01*
X545946Y-204447D01*
X546542Y-204845D01*
X547244Y-204985D01*
X547946Y-204845D01*
X548542Y-204447D01*
X548940Y-203852D01*
X549079Y-203150D01*
X548940Y-202447D01*
X548542Y-201852D01*
X547946Y-201454D01*
X547244Y-201314D01*
X546542Y-201454D01*
X546040Y-201188D01*
X545987Y-200921D01*
X545798Y-200639D01*
X545987Y-200357D01*
X546127Y-199655D01*
X545987Y-198953D01*
X545798Y-198671D01*
X545987Y-198389D01*
X546127Y-197687D01*
X545987Y-196984D01*
X545798Y-196702D01*
X545987Y-196420D01*
X546127Y-195718D01*
X545987Y-195016D01*
X545589Y-194420D01*
X544994Y-194023D01*
X544291Y-193883D01*
D02*
G37*
G36*
X379921Y-199905D02*
X379219Y-200045D01*
X378624Y-200442D01*
X378226Y-201038D01*
X378146Y-201440D01*
X377975Y-201794D01*
X377621Y-201965D01*
X377219Y-202045D01*
X376624Y-202442D01*
X376226Y-203038D01*
X376086Y-203740D01*
X376226Y-204443D01*
X376624Y-205038D01*
X377219Y-205436D01*
X377921Y-205575D01*
X378624Y-205436D01*
X379219Y-205038D01*
X379617Y-204443D01*
X379697Y-204041D01*
X379868Y-203686D01*
X380222Y-203516D01*
X380624Y-203436D01*
X381219Y-203038D01*
X381617Y-202443D01*
X381756Y-201740D01*
X381617Y-201038D01*
X381219Y-200442D01*
X380624Y-200045D01*
X379921Y-199905D01*
D02*
G37*
G36*
X361417Y-201314D02*
X360715Y-201454D01*
X360120Y-201852D01*
X359722Y-202447D01*
X359582Y-203150D01*
X359722Y-203852D01*
X360120Y-204447D01*
X360715Y-204845D01*
X361007Y-204903D01*
X361075Y-205231D01*
X361060Y-205424D01*
X360513Y-205789D01*
X360116Y-206384D01*
X359976Y-207087D01*
X360116Y-207789D01*
X360513Y-208384D01*
X361109Y-208782D01*
X361811Y-208922D01*
X362513Y-208782D01*
X363109Y-208384D01*
X363507Y-207789D01*
X363646Y-207087D01*
X363507Y-206384D01*
X363109Y-205789D01*
X362513Y-205391D01*
X362221Y-205333D01*
X362153Y-205005D01*
X362168Y-204813D01*
X362715Y-204447D01*
X363113Y-203852D01*
X363253Y-203150D01*
X363113Y-202447D01*
X362715Y-201852D01*
X362120Y-201454D01*
X361417Y-201314D01*
D02*
G37*
G36*
X549213Y-206039D02*
X548510Y-206178D01*
X547915Y-206576D01*
X547517Y-207172D01*
X547377Y-207874D01*
X547517Y-208576D01*
X547915Y-209172D01*
X548510Y-209570D01*
X549213Y-209709D01*
X549915Y-209570D01*
X550510Y-209172D01*
X550908Y-208576D01*
X551048Y-207874D01*
X550908Y-207172D01*
X550510Y-206576D01*
X549915Y-206178D01*
X549213Y-206039D01*
D02*
G37*
G36*
X-3528Y-205543D02*
X-13402D01*
Y-215417D01*
X-3528D01*
Y-205543D01*
D02*
G37*
G36*
X86562Y-209347D02*
X85860Y-209487D01*
X85264Y-209885D01*
X84867Y-210480D01*
X84727Y-211183D01*
X84867Y-211885D01*
X84886Y-211915D01*
X84332Y-212285D01*
X83934Y-212880D01*
X83795Y-213583D01*
X83934Y-214285D01*
X84332Y-214880D01*
X84928Y-215278D01*
X85630Y-215418D01*
X86332Y-215278D01*
X86928Y-214880D01*
X87326Y-214285D01*
X87465Y-213583D01*
X87326Y-212880D01*
X87306Y-212851D01*
X87860Y-212480D01*
X88258Y-211885D01*
X88398Y-211183D01*
X88258Y-210480D01*
X87860Y-209885D01*
X87265Y-209487D01*
X86562Y-209347D01*
D02*
G37*
G36*
X544291Y-213568D02*
X543589Y-213708D01*
X542994Y-214105D01*
X542596Y-214701D01*
X542456Y-215403D01*
X542596Y-216106D01*
X542994Y-216701D01*
X543589Y-217099D01*
X544291Y-217238D01*
X544994Y-217099D01*
X545589Y-216701D01*
X545987Y-216106D01*
X546127Y-215403D01*
X545987Y-214701D01*
X545589Y-214105D01*
X544994Y-213708D01*
X544291Y-213568D01*
D02*
G37*
G36*
X102528Y-209747D02*
X101825Y-209887D01*
X101230Y-210285D01*
X100832Y-210880D01*
X100692Y-211583D01*
X100832Y-212285D01*
X100909Y-212401D01*
X100753Y-212778D01*
X100639Y-212896D01*
X100080Y-213269D01*
X99682Y-213865D01*
X99610Y-214230D01*
X99409Y-214700D01*
X98707Y-214840D01*
X98112Y-215238D01*
X97714Y-215833D01*
X97574Y-216535D01*
X97714Y-217238D01*
X97731Y-217264D01*
X97430Y-217714D01*
X97125Y-217653D01*
X96423Y-217793D01*
X95828Y-218191D01*
X95430Y-218786D01*
X95290Y-219488D01*
X95430Y-220191D01*
X95828Y-220786D01*
X96423Y-221184D01*
X97125Y-221323D01*
X97828Y-221184D01*
X98423Y-220786D01*
X98821Y-220191D01*
X98961Y-219488D01*
X98821Y-218786D01*
X98803Y-218760D01*
X99104Y-218310D01*
X99410Y-218371D01*
X100112Y-218231D01*
X100707Y-217833D01*
X101105Y-217238D01*
X101178Y-216872D01*
X101378Y-216402D01*
X102080Y-216263D01*
X102676Y-215865D01*
X103074Y-215269D01*
X103213Y-214567D01*
X103074Y-213865D01*
X102996Y-213749D01*
X103187Y-213287D01*
X103230Y-213278D01*
X103825Y-212880D01*
X104223Y-212285D01*
X104363Y-211583D01*
X104223Y-210880D01*
X103825Y-210285D01*
X103230Y-209887D01*
X102528Y-209747D01*
D02*
G37*
G36*
X635039Y-214306D02*
X634337Y-214446D01*
X633742Y-214844D01*
X633344Y-215439D01*
X633204Y-216142D01*
X633344Y-216844D01*
X633742Y-217439D01*
X634337Y-217837D01*
X635039Y-217977D01*
X635742Y-217837D01*
X636337Y-217439D01*
X636735Y-216844D01*
X636875Y-216142D01*
X636735Y-215439D01*
X636337Y-214844D01*
X635742Y-214446D01*
X635039Y-214306D01*
D02*
G37*
G36*
X680709Y-215094D02*
X680006Y-215234D01*
X679411Y-215631D01*
X679013Y-216227D01*
X678873Y-216929D01*
X679013Y-217631D01*
X679411Y-218227D01*
X680006Y-218625D01*
X680709Y-218764D01*
X681411Y-218625D01*
X682006Y-218227D01*
X682404Y-217631D01*
X682544Y-216929D01*
X682404Y-216227D01*
X682006Y-215631D01*
X681411Y-215234D01*
X680709Y-215094D01*
D02*
G37*
G36*
X671654Y-215488D02*
X670951Y-215627D01*
X670356Y-216025D01*
X669958Y-216620D01*
X669818Y-217323D01*
X669958Y-218025D01*
X670356Y-218621D01*
X670951Y-219018D01*
X671654Y-219158D01*
X672356Y-219018D01*
X672951Y-218621D01*
X673349Y-218025D01*
X673489Y-217323D01*
X673349Y-216620D01*
X672951Y-216025D01*
X672356Y-215627D01*
X671654Y-215488D01*
D02*
G37*
G36*
X652756Y-216669D02*
X652054Y-216808D01*
X651458Y-217206D01*
X651060Y-217802D01*
X650921Y-218504D01*
X651060Y-219206D01*
X651458Y-219802D01*
X652054Y-220199D01*
X652756Y-220339D01*
X653458Y-220199D01*
X654054Y-219802D01*
X654452Y-219206D01*
X654591Y-218504D01*
X654452Y-217802D01*
X654054Y-217206D01*
X653458Y-216808D01*
X652756Y-216669D01*
D02*
G37*
G36*
X361531Y-221590D02*
X360828Y-221730D01*
X360331Y-222062D01*
X359833Y-221730D01*
X359131Y-221590D01*
X358428Y-221730D01*
X357833Y-222128D01*
X357435Y-222723D01*
X357295Y-223425D01*
X356818Y-223459D01*
X356578Y-223412D01*
X356341Y-223459D01*
X356237Y-222933D01*
X355839Y-222338D01*
X355244Y-221940D01*
X354541Y-221800D01*
X353839Y-221940D01*
X353243Y-222338D01*
X352846Y-222933D01*
X352706Y-223636D01*
X352846Y-224338D01*
X353243Y-224934D01*
X353839Y-225331D01*
X354541Y-225471D01*
X354778Y-225424D01*
X354882Y-225949D01*
X355280Y-226545D01*
X355875Y-226942D01*
X356578Y-227082D01*
X357280Y-226942D01*
X357875Y-226545D01*
X358273Y-225949D01*
X358413Y-225247D01*
X358891Y-225213D01*
X359131Y-225260D01*
X359833Y-225121D01*
X360331Y-224788D01*
X360828Y-225121D01*
X361531Y-225260D01*
X362233Y-225121D01*
X362828Y-224723D01*
X363226Y-224128D01*
X363366Y-223425D01*
X363226Y-222723D01*
X362828Y-222128D01*
X362233Y-221730D01*
X361531Y-221590D01*
D02*
G37*
G36*
X86614Y-219621D02*
X85912Y-219761D01*
X85316Y-220159D01*
X84919Y-220754D01*
X84779Y-221457D01*
X84919Y-222159D01*
X85316Y-222754D01*
X85912Y-223152D01*
X86614Y-223292D01*
X87317Y-223152D01*
X87912Y-222754D01*
X88310Y-222159D01*
X88449Y-221457D01*
X88310Y-220754D01*
X87912Y-220159D01*
X87317Y-219761D01*
X86614Y-219621D01*
D02*
G37*
G36*
X63976D02*
X63274Y-219761D01*
X62679Y-220159D01*
X62281Y-220754D01*
X62141Y-221457D01*
X62281Y-222159D01*
X62679Y-222754D01*
X63274Y-223152D01*
X63976Y-223292D01*
X64679Y-223152D01*
X65274Y-222754D01*
X65672Y-222159D01*
X65812Y-221457D01*
X65672Y-220754D01*
X65274Y-220159D01*
X64679Y-219761D01*
X63976Y-219621D01*
D02*
G37*
G36*
X495669Y-220212D02*
X494967Y-220352D01*
X494372Y-220749D01*
X493974Y-221345D01*
X493834Y-222047D01*
X493974Y-222750D01*
X494372Y-223345D01*
X494967Y-223743D01*
X495669Y-223883D01*
X496372Y-223743D01*
X496967Y-223345D01*
X497365Y-222750D01*
X497505Y-222047D01*
X497365Y-221345D01*
X496967Y-220749D01*
X496372Y-220352D01*
X495669Y-220212D01*
D02*
G37*
G36*
X500394Y-220999D02*
X499691Y-221139D01*
X499096Y-221537D01*
X498698Y-222132D01*
X498558Y-222835D01*
X498698Y-223537D01*
X499096Y-224132D01*
X499691Y-224530D01*
X500394Y-224670D01*
X501096Y-224530D01*
X501691Y-224132D01*
X502089Y-223537D01*
X502229Y-222835D01*
X502089Y-222132D01*
X501691Y-221537D01*
X501096Y-221139D01*
X500394Y-220999D01*
D02*
G37*
G36*
X544294Y-222412D02*
X543592Y-222552D01*
X542997Y-222950D01*
X542599Y-223545D01*
X542459Y-224248D01*
X542587Y-224892D01*
X542573Y-224895D01*
X541978Y-225293D01*
X541580Y-225889D01*
X541440Y-226591D01*
X541580Y-227293D01*
X541978Y-227889D01*
X542573Y-228287D01*
X543276Y-228426D01*
X543978Y-228287D01*
X544573Y-227889D01*
X544971Y-227293D01*
X545111Y-226591D01*
X544983Y-225946D01*
X544997Y-225943D01*
X545592Y-225545D01*
X545990Y-224950D01*
X546130Y-224248D01*
X545990Y-223545D01*
X545592Y-222950D01*
X544997Y-222552D01*
X544294Y-222412D01*
D02*
G37*
G36*
X572441Y-225330D02*
X571739Y-225470D01*
X571143Y-225868D01*
X570745Y-226463D01*
X570606Y-227165D01*
X570745Y-227868D01*
X571143Y-228463D01*
X571739Y-228861D01*
X572441Y-229001D01*
X573143Y-228861D01*
X573739Y-228463D01*
X574136Y-227868D01*
X574276Y-227165D01*
X574136Y-226463D01*
X573739Y-225868D01*
X573143Y-225470D01*
X572441Y-225330D01*
D02*
G37*
G36*
X86614Y-225527D02*
X85912Y-225667D01*
X85316Y-226064D01*
X84919Y-226660D01*
X84779Y-227362D01*
X84919Y-228064D01*
X85316Y-228660D01*
X85912Y-229058D01*
X86614Y-229198D01*
X87317Y-229058D01*
X87912Y-228660D01*
X88310Y-228064D01*
X88449Y-227362D01*
X88310Y-226660D01*
X87912Y-226064D01*
X87317Y-225667D01*
X86614Y-225527D01*
D02*
G37*
G36*
X314503Y-223344D02*
X313800Y-223484D01*
X313205Y-223882D01*
X312807Y-224477D01*
X312667Y-225180D01*
X312807Y-225882D01*
X313205Y-226477D01*
X312987Y-226933D01*
X312721Y-227330D01*
X312581Y-228033D01*
X312721Y-228735D01*
X313119Y-229330D01*
X313343Y-229480D01*
Y-230082D01*
X313326Y-230093D01*
X312928Y-230689D01*
X312788Y-231391D01*
X312928Y-232093D01*
X313326Y-232689D01*
X313921Y-233086D01*
X314623Y-233226D01*
X315326Y-233086D01*
X315921Y-232689D01*
X316319Y-232093D01*
X316459Y-231391D01*
X316319Y-230689D01*
X315921Y-230093D01*
X315697Y-229943D01*
Y-229342D01*
X315714Y-229330D01*
X316112Y-228735D01*
X316252Y-228033D01*
X316112Y-227330D01*
X315714Y-226735D01*
X315933Y-226279D01*
X316198Y-225882D01*
X316338Y-225180D01*
X316198Y-224477D01*
X315800Y-223882D01*
X315205Y-223484D01*
X314503Y-223344D01*
D02*
G37*
G36*
X361652Y-233369D02*
X360950Y-233509D01*
X360428Y-233857D01*
X359954Y-233541D01*
X359252Y-233401D01*
X358550Y-233541D01*
X358052Y-233873D01*
X357554Y-233541D01*
X356852Y-233401D01*
X356150Y-233541D01*
X355652Y-233873D01*
X355154Y-233541D01*
X354452Y-233401D01*
X353750Y-233541D01*
X353154Y-233939D01*
X352756Y-234534D01*
X352617Y-235236D01*
X352756Y-235939D01*
X353154Y-236534D01*
X353750Y-236932D01*
X354452Y-237071D01*
X355154Y-236932D01*
X355652Y-236599D01*
X356150Y-236932D01*
X356852Y-237071D01*
X357554Y-236932D01*
X358052Y-236599D01*
X358550Y-236932D01*
X359252Y-237071D01*
X359954Y-236932D01*
X360475Y-236583D01*
X360950Y-236900D01*
X361652Y-237040D01*
X362354Y-236900D01*
X362950Y-236502D01*
X363348Y-235907D01*
X363487Y-235205D01*
X363348Y-234502D01*
X362950Y-233907D01*
X362354Y-233509D01*
X361652Y-233369D01*
D02*
G37*
G36*
X82677Y-230448D02*
X81975Y-230588D01*
X81379Y-230986D01*
X80982Y-231581D01*
X80842Y-232283D01*
X80982Y-232986D01*
X81379Y-233581D01*
X81975Y-233979D01*
X82677Y-234119D01*
X83380Y-233979D01*
X83975Y-233581D01*
X84373Y-232986D01*
X84512Y-232283D01*
X84373Y-231581D01*
X83975Y-230986D01*
X83380Y-230588D01*
X82677Y-230448D01*
D02*
G37*
G36*
X75787D02*
X75085Y-230588D01*
X74490Y-230986D01*
X74092Y-231581D01*
X73952Y-232283D01*
X74092Y-232986D01*
X74490Y-233581D01*
X75085Y-233979D01*
X75787Y-234119D01*
X76490Y-233979D01*
X77085Y-233581D01*
X77483Y-232986D01*
X77623Y-232283D01*
X77483Y-231581D01*
X77085Y-230986D01*
X76490Y-230588D01*
X75787Y-230448D01*
D02*
G37*
G36*
X544291Y-231433D02*
X543589Y-231572D01*
X542994Y-231970D01*
X542596Y-232565D01*
X542456Y-233268D01*
X542596Y-233970D01*
X542994Y-234565D01*
X543589Y-234963D01*
X544291Y-235103D01*
X544994Y-234963D01*
X545589Y-234565D01*
X545987Y-233970D01*
X546127Y-233268D01*
X545987Y-232565D01*
X545589Y-231970D01*
X544994Y-231572D01*
X544291Y-231433D01*
D02*
G37*
G36*
X323819Y-225527D02*
X323117Y-225667D01*
X322521Y-226064D01*
X322123Y-226660D01*
X321984Y-227362D01*
X322123Y-228064D01*
X322521Y-228660D01*
X323117Y-229058D01*
X323207Y-229076D01*
Y-229586D01*
X323117Y-229604D01*
X322521Y-230001D01*
X322123Y-230597D01*
X321984Y-231299D01*
X322123Y-232001D01*
X322521Y-232597D01*
X323117Y-232995D01*
X323548Y-233081D01*
X323952Y-233362D01*
X324092Y-234065D01*
X324490Y-234660D01*
X325085Y-235058D01*
X325787Y-235197D01*
X326490Y-235058D01*
X327085Y-234660D01*
X327483Y-234065D01*
X327623Y-233362D01*
X327483Y-232660D01*
X327085Y-232065D01*
X326490Y-231667D01*
X326241Y-231617D01*
Y-231107D01*
X326490Y-231058D01*
X327085Y-230660D01*
X327483Y-230065D01*
X327623Y-229362D01*
X327483Y-228660D01*
X327085Y-228064D01*
X326490Y-227667D01*
X326118Y-227593D01*
X325736Y-227403D01*
X325593Y-227056D01*
X325515Y-226660D01*
X325117Y-226064D01*
X324521Y-225667D01*
X323819Y-225527D01*
D02*
G37*
G36*
X288583Y-223755D02*
X287880Y-223895D01*
X287285Y-224293D01*
X286887Y-224888D01*
X286747Y-225590D01*
X286887Y-226293D01*
X287163Y-226705D01*
X287285Y-226888D01*
X287053Y-227334D01*
X286891Y-227442D01*
X286493Y-228038D01*
X286354Y-228740D01*
X286493Y-229443D01*
X286813Y-229921D01*
X286493Y-230400D01*
X286354Y-231102D01*
X286493Y-231805D01*
X286752Y-232191D01*
X286362Y-232775D01*
X286222Y-233478D01*
X286362Y-234180D01*
X286759Y-234776D01*
X287355Y-235173D01*
X288057Y-235313D01*
X288759Y-235173D01*
X289355Y-234776D01*
X289753Y-234180D01*
X289892Y-233478D01*
X289753Y-232775D01*
X289494Y-232389D01*
X289884Y-231805D01*
X290024Y-231102D01*
X289884Y-230400D01*
X289565Y-229921D01*
X289884Y-229443D01*
X290024Y-228740D01*
X289884Y-228038D01*
X289609Y-227625D01*
X289487Y-227442D01*
X289719Y-226996D01*
X289880Y-226888D01*
X290278Y-226293D01*
X290418Y-225590D01*
X290278Y-224888D01*
X289880Y-224293D01*
X289285Y-223895D01*
X288583Y-223755D01*
D02*
G37*
G36*
X608661Y-234385D02*
X607959Y-234525D01*
X607364Y-234923D01*
X606966Y-235518D01*
X606826Y-236221D01*
X606966Y-236923D01*
X607364Y-237518D01*
X607959Y-237916D01*
X608661Y-238056D01*
X609364Y-237916D01*
X609959Y-237518D01*
X610357Y-236923D01*
X610497Y-236221D01*
X610357Y-235518D01*
X609959Y-234923D01*
X609364Y-234525D01*
X608661Y-234385D01*
D02*
G37*
G36*
X78740Y-236206D02*
X78038Y-236345D01*
X77442Y-236743D01*
X77045Y-237339D01*
X76905Y-238041D01*
X77045Y-238743D01*
X77442Y-239339D01*
X78038Y-239737D01*
X78740Y-239876D01*
X79443Y-239737D01*
X80038Y-239339D01*
X80436Y-238743D01*
X80575Y-238041D01*
X80436Y-237339D01*
X80038Y-236743D01*
X79443Y-236345D01*
X78740Y-236206D01*
D02*
G37*
G36*
X637008Y-236747D02*
X636306Y-236887D01*
X635710Y-237285D01*
X635312Y-237880D01*
X635173Y-238583D01*
X635312Y-239285D01*
X635710Y-239880D01*
X636306Y-240278D01*
X637008Y-240418D01*
X637710Y-240278D01*
X638306Y-239880D01*
X638703Y-239285D01*
X638843Y-238583D01*
X638703Y-237880D01*
X638306Y-237285D01*
X637710Y-236887D01*
X637008Y-236747D01*
D02*
G37*
G36*
X-23622Y-227495D02*
X-24324Y-227635D01*
X-24920Y-228033D01*
X-25318Y-228628D01*
X-25457Y-229331D01*
X-25318Y-230033D01*
X-24920Y-230628D01*
X-24324Y-231026D01*
X-24234Y-231044D01*
Y-231554D01*
X-24324Y-231572D01*
X-24920Y-231970D01*
X-25318Y-232565D01*
X-25457Y-233268D01*
X-25318Y-233970D01*
X-24920Y-234565D01*
X-24324Y-234963D01*
X-24234Y-234981D01*
Y-235491D01*
X-24324Y-235509D01*
X-24920Y-235907D01*
X-25318Y-236502D01*
X-25457Y-237205D01*
X-25318Y-237907D01*
X-24920Y-238502D01*
X-24324Y-238900D01*
X-24234Y-238918D01*
Y-239428D01*
X-24324Y-239446D01*
X-24920Y-239844D01*
X-25318Y-240439D01*
X-25457Y-241142D01*
X-25318Y-241844D01*
X-24920Y-242439D01*
X-24324Y-242837D01*
X-23622Y-242977D01*
X-22920Y-242837D01*
X-22324Y-242439D01*
X-21926Y-241844D01*
X-21787Y-241142D01*
X-21926Y-240439D01*
X-22324Y-239844D01*
X-22920Y-239446D01*
X-23010Y-239428D01*
Y-238918D01*
X-22920Y-238900D01*
X-22324Y-238502D01*
X-21926Y-237907D01*
X-21787Y-237205D01*
X-21926Y-236502D01*
X-22324Y-235907D01*
X-22920Y-235509D01*
X-23010Y-235491D01*
Y-234981D01*
X-22920Y-234963D01*
X-22324Y-234565D01*
X-21926Y-233970D01*
X-21787Y-233268D01*
X-21926Y-232565D01*
X-22324Y-231970D01*
X-22920Y-231572D01*
X-23010Y-231554D01*
Y-231044D01*
X-22920Y-231026D01*
X-22324Y-230628D01*
X-21926Y-230033D01*
X-21787Y-229331D01*
X-21926Y-228628D01*
X-22324Y-228033D01*
X-22920Y-227635D01*
X-23622Y-227495D01*
D02*
G37*
G36*
X608661Y-240291D02*
X607959Y-240430D01*
X607364Y-240828D01*
X606966Y-241424D01*
X606826Y-242126D01*
X606966Y-242828D01*
X607364Y-243424D01*
X607959Y-243822D01*
X608661Y-243961D01*
X609364Y-243822D01*
X609959Y-243424D01*
X610357Y-242828D01*
X610497Y-242126D01*
X610357Y-241424D01*
X609959Y-240828D01*
X609364Y-240430D01*
X608661Y-240291D01*
D02*
G37*
G36*
X590551Y-240684D02*
X589849Y-240824D01*
X589254Y-241222D01*
X588856Y-241817D01*
X588716Y-242520D01*
X588856Y-243222D01*
X589254Y-243817D01*
X589849Y-244215D01*
X590551Y-244355D01*
X591254Y-244215D01*
X591849Y-243817D01*
X592247Y-243222D01*
X592386Y-242520D01*
X592247Y-241817D01*
X591849Y-241222D01*
X591254Y-240824D01*
X590551Y-240684D01*
D02*
G37*
G36*
X323850Y-235369D02*
X323148Y-235509D01*
X322553Y-235907D01*
X322155Y-236502D01*
X322015Y-237205D01*
X322155Y-237907D01*
X322553Y-238502D01*
X323148Y-238900D01*
X323318Y-238934D01*
Y-239444D01*
X323148Y-239478D01*
X322553Y-239876D01*
X322155Y-240471D01*
X322015Y-241173D01*
X322155Y-241876D01*
X322553Y-242471D01*
X323148Y-242869D01*
X323850Y-243008D01*
X324008Y-243487D01*
X324092Y-243907D01*
X324490Y-244502D01*
X325085Y-244900D01*
X325787Y-245040D01*
X326490Y-244900D01*
X327085Y-244502D01*
X327483Y-243907D01*
X327623Y-243205D01*
X327483Y-242502D01*
X327085Y-241907D01*
X326490Y-241509D01*
X326241Y-241460D01*
Y-240950D01*
X326490Y-240900D01*
X327085Y-240502D01*
X327483Y-239907D01*
X327623Y-239205D01*
X327483Y-238502D01*
X327085Y-237907D01*
X326490Y-237509D01*
X326148Y-237441D01*
X325740Y-237233D01*
X325623Y-236892D01*
X325546Y-236502D01*
X325148Y-235907D01*
X324553Y-235509D01*
X323850Y-235369D01*
D02*
G37*
G36*
X314658Y-242939D02*
X313955Y-243079D01*
X313360Y-243477D01*
X312962Y-244072D01*
X312823Y-244775D01*
X312962Y-245477D01*
X313360Y-246073D01*
X313955Y-246470D01*
X314658Y-246610D01*
X315360Y-246470D01*
X315955Y-246073D01*
X316353Y-245477D01*
X316493Y-244775D01*
X316353Y-244072D01*
X315955Y-243477D01*
X315360Y-243079D01*
X314658Y-242939D01*
D02*
G37*
G36*
X288057Y-243260D02*
X287355Y-243399D01*
X286759Y-243797D01*
X286362Y-244393D01*
X286222Y-245095D01*
X286362Y-245797D01*
X286759Y-246393D01*
X286826Y-246437D01*
X286493Y-246936D01*
X286354Y-247638D01*
X286493Y-248340D01*
X286891Y-248936D01*
X287487Y-249333D01*
X288189Y-249473D01*
X288891Y-249333D01*
X289487Y-248936D01*
X289884Y-248340D01*
X290024Y-247638D01*
X289884Y-246936D01*
X289487Y-246340D01*
X289420Y-246295D01*
X289753Y-245797D01*
X289893Y-245095D01*
X289753Y-244393D01*
X289355Y-243797D01*
X288759Y-243399D01*
X288057Y-243260D01*
D02*
G37*
G36*
X585039Y-247771D02*
X584337Y-247911D01*
X583742Y-248309D01*
X583344Y-248904D01*
X583204Y-249606D01*
X583344Y-250309D01*
X583742Y-250904D01*
X584337Y-251302D01*
X585039Y-251442D01*
X585742Y-251302D01*
X586337Y-250904D01*
X586735Y-250309D01*
X586875Y-249606D01*
X586735Y-248904D01*
X586337Y-248309D01*
X585742Y-247911D01*
X585039Y-247771D01*
D02*
G37*
G36*
X360204Y-251149D02*
X359502Y-251289D01*
X358907Y-251687D01*
X358509Y-252282D01*
X358369Y-252984D01*
X358509Y-253687D01*
X358907Y-254282D01*
X359502Y-254680D01*
X360204Y-254819D01*
X360907Y-254680D01*
X361502Y-254282D01*
X361900Y-253687D01*
X362040Y-252984D01*
X361900Y-252282D01*
X361502Y-251687D01*
X360907Y-251289D01*
X360204Y-251149D01*
D02*
G37*
G36*
X585433Y-252102D02*
X584731Y-252241D01*
X584135Y-252639D01*
X583738Y-253235D01*
X583598Y-253937D01*
X583738Y-254639D01*
X584135Y-255235D01*
X584395Y-255408D01*
Y-256009D01*
X584135Y-256183D01*
X583738Y-256778D01*
X583719Y-256869D01*
X583210D01*
X583192Y-256778D01*
X582794Y-256183D01*
X582198Y-255785D01*
X581496Y-255645D01*
X580794Y-255785D01*
X580198Y-256183D01*
X580025Y-256442D01*
X579424D01*
X579250Y-256183D01*
X578655Y-255785D01*
X577953Y-255645D01*
X577250Y-255785D01*
X576655Y-256183D01*
X576257Y-256778D01*
X576118Y-257480D01*
X576257Y-258183D01*
X576655Y-258778D01*
X577250Y-259176D01*
X577953Y-259316D01*
X578655Y-259176D01*
X579250Y-258778D01*
X579424Y-258519D01*
X580025D01*
X580198Y-258778D01*
X580794Y-259176D01*
X581496Y-259316D01*
X582198Y-259176D01*
X582794Y-258778D01*
X583192Y-258183D01*
X583210Y-258092D01*
X583719D01*
X583738Y-258183D01*
X584135Y-258778D01*
X584731Y-259176D01*
X585433Y-259316D01*
X586135Y-259176D01*
X586731Y-258778D01*
X587129Y-258183D01*
X587268Y-257480D01*
X587129Y-256778D01*
X586731Y-256183D01*
X586472Y-256009D01*
Y-255408D01*
X586731Y-255235D01*
X587129Y-254639D01*
X587268Y-253937D01*
X587129Y-253235D01*
X586731Y-252639D01*
X586135Y-252241D01*
X585433Y-252102D01*
D02*
G37*
G36*
X563386Y-256039D02*
X562683Y-256178D01*
X562088Y-256576D01*
X561690Y-257172D01*
X561551Y-257874D01*
X561690Y-258576D01*
X562088Y-259172D01*
X562683Y-259570D01*
X563386Y-259709D01*
X564088Y-259570D01*
X564684Y-259172D01*
X565081Y-258576D01*
X565221Y-257874D01*
X565081Y-257172D01*
X564684Y-256576D01*
X564088Y-256178D01*
X563386Y-256039D01*
D02*
G37*
G36*
X572441Y-256433D02*
X571739Y-256572D01*
X571143Y-256970D01*
X570745Y-257565D01*
X570606Y-258268D01*
X570745Y-258970D01*
X571143Y-259565D01*
X571739Y-259963D01*
X572441Y-260103D01*
X573143Y-259963D01*
X573739Y-259565D01*
X574136Y-258970D01*
X574276Y-258268D01*
X574136Y-257565D01*
X573739Y-256970D01*
X573143Y-256572D01*
X572441Y-256433D01*
D02*
G37*
G36*
X556628Y-256207D02*
X555925Y-256347D01*
X555330Y-256744D01*
X554932Y-257340D01*
X554792Y-258042D01*
X554932Y-258744D01*
X555330Y-259340D01*
X555693Y-259582D01*
X555784Y-260093D01*
X555751Y-260176D01*
X555391Y-260715D01*
X555251Y-261417D01*
X555391Y-262120D01*
X555789Y-262715D01*
X556384Y-263113D01*
X557087Y-263253D01*
X557789Y-263113D01*
X558384Y-262715D01*
X558782Y-262120D01*
X558922Y-261417D01*
X558782Y-260715D01*
X558384Y-260120D01*
X558021Y-259877D01*
X557930Y-259366D01*
X557964Y-259283D01*
X558323Y-258744D01*
X558463Y-258042D01*
X558323Y-257340D01*
X557926Y-256744D01*
X557330Y-256347D01*
X556628Y-256207D01*
D02*
G37*
G36*
X120079Y-261551D02*
X119376Y-261690D01*
X118781Y-262088D01*
X118383Y-262684D01*
X118244Y-263386D01*
X118383Y-264088D01*
X118781Y-264684D01*
X119376Y-265081D01*
X120079Y-265221D01*
X120781Y-265081D01*
X121377Y-264684D01*
X121774Y-264088D01*
X121914Y-263386D01*
X121774Y-262684D01*
X121377Y-262088D01*
X120781Y-261690D01*
X120079Y-261551D01*
D02*
G37*
G36*
X106299Y-261796D02*
X105597Y-261936D01*
X105001Y-262334D01*
X104604Y-262929D01*
X104464Y-263632D01*
X104604Y-264334D01*
X105001Y-264929D01*
X105597Y-265327D01*
X106299Y-265467D01*
X107001Y-265327D01*
X107597Y-264929D01*
X107995Y-264334D01*
X108134Y-263632D01*
X107995Y-262929D01*
X107597Y-262334D01*
X107001Y-261936D01*
X106299Y-261796D01*
D02*
G37*
G36*
X85630Y-261944D02*
X84928Y-262084D01*
X84332Y-262482D01*
X83934Y-263077D01*
X83795Y-263779D01*
X83934Y-264482D01*
X84267Y-264980D01*
X83934Y-265477D01*
X83795Y-266179D01*
X83934Y-266882D01*
X84332Y-267477D01*
X84928Y-267875D01*
X85630Y-268015D01*
X86332Y-267875D01*
X86928Y-267477D01*
X87326Y-266882D01*
X87465Y-266179D01*
X87326Y-265477D01*
X86993Y-264980D01*
X87326Y-264482D01*
X87465Y-263779D01*
X87326Y-263077D01*
X86928Y-262482D01*
X86332Y-262084D01*
X85630Y-261944D01*
D02*
G37*
G36*
X588189Y-261551D02*
X587487Y-261690D01*
X586891Y-262088D01*
X586493Y-262684D01*
X586354Y-263386D01*
X586493Y-264088D01*
X586891Y-264684D01*
X587487Y-265081D01*
X588189Y-265221D01*
X588736Y-265112D01*
X589064Y-265522D01*
X588856Y-265833D01*
X588716Y-266535D01*
X588856Y-267238D01*
X589254Y-267833D01*
X589849Y-268231D01*
X590551Y-268371D01*
X591254Y-268231D01*
X591849Y-267833D01*
X592247Y-267238D01*
X592386Y-266535D01*
X592247Y-265833D01*
X591849Y-265238D01*
X591254Y-264840D01*
X590551Y-264700D01*
X590004Y-264809D01*
X589677Y-264399D01*
X589885Y-264088D01*
X590024Y-263386D01*
X589885Y-262684D01*
X589487Y-262088D01*
X588891Y-261690D01*
X588189Y-261551D01*
D02*
G37*
G36*
X-3528Y-258693D02*
X-13402D01*
Y-268567D01*
X-3528D01*
Y-258693D01*
D02*
G37*
G36*
X512402Y-260123D02*
X511699Y-260263D01*
X511104Y-260661D01*
X510706Y-261256D01*
X510566Y-261958D01*
X510706Y-262661D01*
X511104Y-263256D01*
X511144Y-263283D01*
Y-263783D01*
X511104Y-263810D01*
X510706Y-264406D01*
X510566Y-265108D01*
X510706Y-265810D01*
X511037Y-266305D01*
X511245Y-266767D01*
X510847Y-267363D01*
X510708Y-268065D01*
X510847Y-268767D01*
X511236Y-269349D01*
X510962Y-269760D01*
X510822Y-270462D01*
X510962Y-271165D01*
X511360Y-271760D01*
X511955Y-272158D01*
X512657Y-272298D01*
X513360Y-272158D01*
X513955Y-271760D01*
X514353Y-271165D01*
X514493Y-270462D01*
X514353Y-269760D01*
X513964Y-269178D01*
X514239Y-268767D01*
X514378Y-268065D01*
X514239Y-267363D01*
X513908Y-266868D01*
X513699Y-266406D01*
X514097Y-265810D01*
X514237Y-265108D01*
X514097Y-264406D01*
X513699Y-263810D01*
X513659Y-263783D01*
Y-263283D01*
X513699Y-263256D01*
X514097Y-262661D01*
X514237Y-261958D01*
X514097Y-261256D01*
X513699Y-260661D01*
X513104Y-260263D01*
X512402Y-260123D01*
D02*
G37*
G36*
X545276Y-269031D02*
X544573Y-269171D01*
X543978Y-269568D01*
X543580Y-270164D01*
X543440Y-270866D01*
X543580Y-271568D01*
X543978Y-272164D01*
X544573Y-272562D01*
X545276Y-272701D01*
X545978Y-272562D01*
X546573Y-272164D01*
X546971Y-271568D01*
X547111Y-270866D01*
X546971Y-270164D01*
X546573Y-269568D01*
X545978Y-269171D01*
X545276Y-269031D01*
D02*
G37*
G36*
X325984Y-270606D02*
X325282Y-270745D01*
X324687Y-271143D01*
X324289Y-271739D01*
X324149Y-272441D01*
X324289Y-273143D01*
X324687Y-273739D01*
X325282Y-274136D01*
X325984Y-274276D01*
X326687Y-274136D01*
X327282Y-273739D01*
X327680Y-273143D01*
X327819Y-272441D01*
X327680Y-271739D01*
X327282Y-271143D01*
X326687Y-270745D01*
X325984Y-270606D01*
D02*
G37*
G36*
X360236Y-260350D02*
X359534Y-260490D01*
X358939Y-260888D01*
X358541Y-261484D01*
X358401Y-262186D01*
X358541Y-262888D01*
X358939Y-263484D01*
X359534Y-263881D01*
X359783Y-263931D01*
Y-264441D01*
X359534Y-264490D01*
X358939Y-264888D01*
X358541Y-265483D01*
X358401Y-266186D01*
X358541Y-266888D01*
X358873Y-267386D01*
X358541Y-267883D01*
X358401Y-268586D01*
X358541Y-269288D01*
X358939Y-269883D01*
X359534Y-270281D01*
X359542Y-270283D01*
Y-270793D01*
X359534Y-270794D01*
X358939Y-271192D01*
X358541Y-271787D01*
X358401Y-272490D01*
X358541Y-273192D01*
X358939Y-273787D01*
X359534Y-274185D01*
X360236Y-274325D01*
X360939Y-274185D01*
X361534Y-273787D01*
X361932Y-273192D01*
X362071Y-272490D01*
X361932Y-271787D01*
X361534Y-271192D01*
X360939Y-270794D01*
X360931Y-270793D01*
Y-270283D01*
X360939Y-270281D01*
X361534Y-269883D01*
X361932Y-269288D01*
X362071Y-268586D01*
X361932Y-267883D01*
X361599Y-267386D01*
X361932Y-266888D01*
X362071Y-266186D01*
X361932Y-265483D01*
X361534Y-264888D01*
X360939Y-264490D01*
X360689Y-264441D01*
Y-263931D01*
X360939Y-263881D01*
X361534Y-263484D01*
X361932Y-262888D01*
X362071Y-262186D01*
X361932Y-261484D01*
X361534Y-260888D01*
X360939Y-260490D01*
X360236Y-260350D01*
D02*
G37*
G36*
X340904Y-271286D02*
X340092Y-271448D01*
X339403Y-271908D01*
X338942Y-272597D01*
X338780Y-273410D01*
X338942Y-274223D01*
X339403Y-274912D01*
X340092Y-275372D01*
X340904Y-275534D01*
X341717Y-275372D01*
X342406Y-274912D01*
X342866Y-274223D01*
X343028Y-273410D01*
X342866Y-272597D01*
X342406Y-271908D01*
X341717Y-271448D01*
X340904Y-271286D01*
D02*
G37*
G36*
X528395Y-271296D02*
X527583Y-271458D01*
X526894Y-271918D01*
X526433Y-272607D01*
X526271Y-273420D01*
X526433Y-274233D01*
X526894Y-274921D01*
X527583Y-275382D01*
X528395Y-275544D01*
X529208Y-275382D01*
X529897Y-274921D01*
X530358Y-274233D01*
X530519Y-273420D01*
X530358Y-272607D01*
X529897Y-271918D01*
X529208Y-271458D01*
X528395Y-271296D01*
D02*
G37*
G36*
X651575Y-273362D02*
X650873Y-273501D01*
X650277Y-273899D01*
X649879Y-274495D01*
X649740Y-275197D01*
X649879Y-275899D01*
X650277Y-276495D01*
X650873Y-276892D01*
X651575Y-277032D01*
X652277Y-276892D01*
X652873Y-276495D01*
X653270Y-275899D01*
X653410Y-275197D01*
X653270Y-274495D01*
X652873Y-273899D01*
X652277Y-273501D01*
X651575Y-273362D01*
D02*
G37*
G36*
X545276D02*
X544573Y-273501D01*
X543978Y-273899D01*
X543580Y-274495D01*
X543440Y-275197D01*
X543580Y-275899D01*
X543978Y-276495D01*
X544573Y-276892D01*
X545276Y-277032D01*
X545978Y-276892D01*
X546573Y-276495D01*
X546971Y-275899D01*
X547111Y-275197D01*
X546971Y-274495D01*
X546573Y-273899D01*
X545978Y-273501D01*
X545276Y-273362D01*
D02*
G37*
G36*
X87598Y-273755D02*
X86896Y-273895D01*
X86301Y-274293D01*
X85903Y-274888D01*
X85763Y-275590D01*
X85903Y-276293D01*
X86301Y-276888D01*
X86896Y-277286D01*
X87598Y-277426D01*
X88301Y-277286D01*
X88896Y-276888D01*
X89294Y-276293D01*
X89434Y-275590D01*
X89294Y-274888D01*
X88896Y-274293D01*
X88301Y-273895D01*
X87598Y-273755D01*
D02*
G37*
G36*
X63976D02*
X63274Y-273895D01*
X62679Y-274293D01*
X62281Y-274888D01*
X62141Y-275590D01*
X62281Y-276293D01*
X62679Y-276888D01*
X63274Y-277286D01*
X63976Y-277426D01*
X64679Y-277286D01*
X65274Y-276888D01*
X65672Y-276293D01*
X65812Y-275590D01*
X65672Y-274888D01*
X65274Y-274293D01*
X64679Y-273895D01*
X63976Y-273755D01*
D02*
G37*
G36*
X630577Y-276166D02*
X629874Y-276306D01*
X629279Y-276704D01*
X628881Y-277299D01*
X628741Y-278001D01*
X628881Y-278704D01*
X629279Y-279299D01*
X629874Y-279697D01*
X630577Y-279837D01*
X631279Y-279697D01*
X631874Y-279299D01*
X632272Y-278704D01*
X632412Y-278001D01*
X632272Y-277299D01*
X631874Y-276704D01*
X631279Y-276306D01*
X630577Y-276166D01*
D02*
G37*
G36*
X657087Y-277692D02*
X656384Y-277832D01*
X655789Y-278230D01*
X655391Y-278825D01*
X655251Y-279528D01*
X655391Y-280230D01*
X655789Y-280825D01*
X656384Y-281223D01*
X657087Y-281363D01*
X657789Y-281223D01*
X658384Y-280825D01*
X658782Y-280230D01*
X658922Y-279528D01*
X658782Y-278825D01*
X658384Y-278230D01*
X657789Y-277832D01*
X657087Y-277692D01*
D02*
G37*
G36*
X648819Y-276905D02*
X648117Y-277045D01*
X647521Y-277442D01*
X647123Y-278038D01*
X646984Y-278740D01*
X647123Y-279443D01*
X647521Y-280038D01*
X648117Y-280436D01*
X648819Y-280575D01*
X649521Y-280436D01*
X650117Y-280038D01*
X650118Y-280035D01*
X650649Y-280141D01*
X650667Y-280230D01*
X651064Y-280825D01*
X651660Y-281223D01*
X652362Y-281363D01*
X653064Y-281223D01*
X653660Y-280825D01*
X654058Y-280230D01*
X654198Y-279528D01*
X654058Y-278825D01*
X653660Y-278230D01*
X653064Y-277832D01*
X652362Y-277692D01*
X651660Y-277832D01*
X651064Y-278230D01*
X651063Y-278232D01*
X650532Y-278127D01*
X650515Y-278038D01*
X650117Y-277442D01*
X649521Y-277045D01*
X648819Y-276905D01*
D02*
G37*
G36*
X650000Y-282023D02*
X649298Y-282163D01*
X648702Y-282561D01*
X648529Y-282820D01*
X647928D01*
X647754Y-282561D01*
X647159Y-282163D01*
X646457Y-282023D01*
X645754Y-282163D01*
X645159Y-282561D01*
X644761Y-283156D01*
X644621Y-283858D01*
X644761Y-284561D01*
X645159Y-285156D01*
X645754Y-285554D01*
X646457Y-285694D01*
X647159Y-285554D01*
X647754Y-285156D01*
X647928Y-284897D01*
X648529D01*
X648702Y-285156D01*
X649298Y-285554D01*
X650000Y-285694D01*
X650702Y-285554D01*
X651298Y-285156D01*
X651696Y-284561D01*
X651835Y-283858D01*
X651696Y-283156D01*
X651298Y-282561D01*
X650702Y-282163D01*
X650000Y-282023D01*
D02*
G37*
G36*
X87598Y-279661D02*
X86896Y-279801D01*
X86301Y-280198D01*
X85903Y-280794D01*
X85763Y-281496D01*
X85903Y-282198D01*
X86301Y-282794D01*
X86896Y-283192D01*
X87598Y-283331D01*
X88301Y-283192D01*
X88896Y-282794D01*
X89294Y-282198D01*
X89434Y-281496D01*
X89294Y-280794D01*
X88896Y-280198D01*
X88301Y-279801D01*
X87598Y-279661D01*
D02*
G37*
G36*
X26575Y-281629D02*
X25872Y-281769D01*
X25277Y-282167D01*
X24879Y-282762D01*
X24739Y-283465D01*
X24879Y-284167D01*
X25277Y-284762D01*
X25872Y-285160D01*
X26575Y-285300D01*
X27277Y-285160D01*
X27872Y-284762D01*
X28270Y-284167D01*
X28410Y-283465D01*
X28270Y-282762D01*
X27872Y-282167D01*
X27277Y-281769D01*
X26575Y-281629D01*
D02*
G37*
G36*
X654331Y-282023D02*
X653628Y-282163D01*
X653033Y-282561D01*
X652635Y-283156D01*
X652495Y-283858D01*
X652635Y-284561D01*
X653033Y-285156D01*
X653628Y-285554D01*
X654331Y-285694D01*
X655033Y-285554D01*
X655628Y-285156D01*
X656026Y-284561D01*
X656166Y-283858D01*
X656026Y-283156D01*
X655628Y-282561D01*
X655033Y-282163D01*
X654331Y-282023D01*
D02*
G37*
G36*
X75787Y-283598D02*
X75085Y-283737D01*
X74490Y-284135D01*
X74092Y-284731D01*
X73952Y-285433D01*
X74092Y-286135D01*
X74490Y-286731D01*
X75085Y-287129D01*
X75787Y-287268D01*
X76490Y-287129D01*
X77085Y-286731D01*
X77483Y-286135D01*
X77623Y-285433D01*
X77483Y-284731D01*
X77085Y-284135D01*
X76490Y-283737D01*
X75787Y-283598D01*
D02*
G37*
G36*
X569548Y-285388D02*
X568845Y-285528D01*
X568250Y-285926D01*
X567852Y-286521D01*
X567712Y-287223D01*
X567852Y-287926D01*
X568250Y-288521D01*
X568845Y-288919D01*
X569548Y-289058D01*
X570250Y-288919D01*
X570845Y-288521D01*
X571243Y-287926D01*
X571383Y-287223D01*
X571243Y-286521D01*
X570845Y-285926D01*
X570250Y-285528D01*
X569548Y-285388D01*
D02*
G37*
G36*
X544909Y-285601D02*
X544207Y-285741D01*
X543611Y-286139D01*
X543214Y-286734D01*
X543074Y-287437D01*
X543214Y-288139D01*
X543611Y-288734D01*
X544207Y-289132D01*
X544909Y-289272D01*
X545611Y-289132D01*
X546207Y-288734D01*
X546605Y-288139D01*
X546744Y-287437D01*
X546605Y-286734D01*
X546207Y-286139D01*
X545611Y-285741D01*
X544909Y-285601D01*
D02*
G37*
G36*
X81880Y-285747D02*
X81177Y-285887D01*
X80582Y-286285D01*
X80184Y-286880D01*
X80044Y-287582D01*
X80184Y-288285D01*
X80582Y-288880D01*
X81177Y-289278D01*
X81880Y-289418D01*
X82582Y-289278D01*
X83177Y-288880D01*
X83575Y-288285D01*
X83715Y-287582D01*
X83575Y-286880D01*
X83177Y-286285D01*
X82582Y-285887D01*
X81880Y-285747D01*
D02*
G37*
G36*
X612598Y-289897D02*
X611896Y-290037D01*
X611301Y-290435D01*
X610903Y-291030D01*
X610763Y-291732D01*
X610903Y-292435D01*
X611301Y-293030D01*
X611896Y-293428D01*
X612598Y-293567D01*
X613301Y-293428D01*
X613896Y-293030D01*
X614294Y-292435D01*
X614434Y-291732D01*
X614294Y-291030D01*
X613896Y-290435D01*
X613301Y-290037D01*
X612598Y-289897D01*
D02*
G37*
G36*
X678441Y-290751D02*
X677738Y-290891D01*
X677143Y-291289D01*
X676745Y-291884D01*
X676605Y-292586D01*
X676745Y-293289D01*
X677143Y-293884D01*
X677738Y-294282D01*
X678441Y-294422D01*
X679143Y-294282D01*
X679738Y-293884D01*
X680136Y-293289D01*
X680276Y-292586D01*
X680136Y-291884D01*
X679738Y-291289D01*
X679143Y-290891D01*
X678441Y-290751D01*
D02*
G37*
G36*
X565354Y-291078D02*
X564652Y-291218D01*
X564057Y-291616D01*
X563659Y-292211D01*
X563519Y-292913D01*
X563659Y-293616D01*
X564057Y-294211D01*
X564652Y-294609D01*
X565354Y-294749D01*
X566057Y-294609D01*
X566652Y-294211D01*
X567050Y-293616D01*
X567190Y-292913D01*
X567050Y-292211D01*
X566652Y-291616D01*
X566057Y-291218D01*
X565354Y-291078D01*
D02*
G37*
G36*
X582874Y-292456D02*
X582172Y-292596D01*
X581576Y-292994D01*
X581178Y-293589D01*
X581039Y-294291D01*
X581178Y-294994D01*
X581576Y-295589D01*
X582172Y-295987D01*
X582874Y-296127D01*
X583576Y-295987D01*
X584172Y-295589D01*
X584570Y-294994D01*
X584709Y-294291D01*
X584570Y-293589D01*
X584172Y-292994D01*
X583576Y-292596D01*
X582874Y-292456D01*
D02*
G37*
G36*
X-23622Y-280645D02*
X-24324Y-280785D01*
X-24920Y-281183D01*
X-25318Y-281778D01*
X-25457Y-282480D01*
X-25318Y-283183D01*
X-24920Y-283778D01*
X-24324Y-284176D01*
X-24234Y-284194D01*
Y-284704D01*
X-24324Y-284722D01*
X-24920Y-285120D01*
X-25318Y-285715D01*
X-25457Y-286417D01*
X-25318Y-287120D01*
X-24920Y-287715D01*
X-24324Y-288113D01*
X-24234Y-288131D01*
Y-288641D01*
X-24324Y-288659D01*
X-24920Y-289057D01*
X-25318Y-289652D01*
X-25457Y-290354D01*
X-25318Y-291057D01*
X-24920Y-291652D01*
X-24324Y-292050D01*
X-24234Y-292068D01*
Y-292578D01*
X-24324Y-292596D01*
X-24920Y-292994D01*
X-25318Y-293589D01*
X-25457Y-294291D01*
X-25318Y-294994D01*
X-24920Y-295589D01*
X-24324Y-295987D01*
X-23622Y-296127D01*
X-22920Y-295987D01*
X-22324Y-295589D01*
X-21926Y-294994D01*
X-21787Y-294291D01*
X-21926Y-293589D01*
X-22324Y-292994D01*
X-22920Y-292596D01*
X-23010Y-292578D01*
Y-292068D01*
X-22920Y-292050D01*
X-22324Y-291652D01*
X-21926Y-291057D01*
X-21787Y-290354D01*
X-21926Y-289652D01*
X-22324Y-289057D01*
X-22920Y-288659D01*
X-23010Y-288641D01*
Y-288131D01*
X-22920Y-288113D01*
X-22324Y-287715D01*
X-21926Y-287120D01*
X-21787Y-286417D01*
X-21926Y-285715D01*
X-22324Y-285120D01*
X-22920Y-284722D01*
X-23010Y-284704D01*
Y-284194D01*
X-22920Y-284176D01*
X-22324Y-283778D01*
X-21926Y-283183D01*
X-21787Y-282480D01*
X-21926Y-281778D01*
X-22324Y-281183D01*
X-22920Y-280785D01*
X-23622Y-280645D01*
D02*
G37*
G36*
X627559Y-294621D02*
X626857Y-294761D01*
X626261Y-295159D01*
X625864Y-295754D01*
X625724Y-296457D01*
X625864Y-297159D01*
X626261Y-297754D01*
X626857Y-298152D01*
X627559Y-298292D01*
X628261Y-298152D01*
X628857Y-297754D01*
X629255Y-297159D01*
X629394Y-296457D01*
X629255Y-295754D01*
X628857Y-295159D01*
X628261Y-294761D01*
X627559Y-294621D01*
D02*
G37*
G36*
X678346Y-295409D02*
X677644Y-295549D01*
X677049Y-295946D01*
X676651Y-296542D01*
X676511Y-297244D01*
X676651Y-297946D01*
X677049Y-298542D01*
X677644Y-298940D01*
X678346Y-299079D01*
X679049Y-298940D01*
X679644Y-298542D01*
X680042Y-297946D01*
X680182Y-297244D01*
X680042Y-296542D01*
X679644Y-295946D01*
X679049Y-295549D01*
X678346Y-295409D01*
D02*
G37*
G36*
X588976Y-300921D02*
X588274Y-301060D01*
X587679Y-301458D01*
X587281Y-302054D01*
X587141Y-302756D01*
X587281Y-303458D01*
X587679Y-304054D01*
X588274Y-304451D01*
X588976Y-304591D01*
X589679Y-304451D01*
X590274Y-304054D01*
X590672Y-303458D01*
X590812Y-302756D01*
X590672Y-302054D01*
X590274Y-301458D01*
X589679Y-301060D01*
X588976Y-300921D01*
D02*
G37*
G36*
X579528Y-301314D02*
X578825Y-301454D01*
X578230Y-301852D01*
X577832Y-302447D01*
X577692Y-303150D01*
X577832Y-303852D01*
X578230Y-304447D01*
X578825Y-304845D01*
X579528Y-304985D01*
X580230Y-304845D01*
X580825Y-304447D01*
X581223Y-303852D01*
X581363Y-303150D01*
X581223Y-302447D01*
X580825Y-301852D01*
X580230Y-301454D01*
X579528Y-301314D01*
D02*
G37*
G36*
X453937Y-304907D02*
X453235Y-305046D01*
X452639Y-305444D01*
X452479D01*
X451883Y-305046D01*
X451181Y-304907D01*
X450479Y-305046D01*
X449916Y-305422D01*
X449769Y-305485D01*
X449443D01*
X449297Y-305422D01*
X448734Y-305046D01*
X448032Y-304907D01*
X447329Y-305046D01*
X447039Y-305240D01*
X446654Y-305409D01*
X446269Y-305240D01*
X445978Y-305046D01*
X445276Y-304907D01*
X444573Y-305046D01*
X444010Y-305422D01*
X443864Y-305485D01*
X443538D01*
X443391Y-305422D01*
X442828Y-305046D01*
X442126Y-304907D01*
X441424Y-305046D01*
X441133Y-305240D01*
X440748Y-305409D01*
X440363Y-305240D01*
X440072Y-305046D01*
X439370Y-304907D01*
X438668Y-305046D01*
X438105Y-305422D01*
X437958Y-305485D01*
X437632D01*
X437486Y-305422D01*
X436923Y-305046D01*
X436221Y-304907D01*
X435518Y-305046D01*
X434923Y-305444D01*
X434762D01*
X434167Y-305046D01*
X433465Y-304907D01*
X432762Y-305046D01*
X432167Y-305444D01*
X431769Y-306039D01*
X431629Y-306742D01*
X431769Y-307444D01*
X432167Y-308039D01*
X432762Y-308437D01*
X433465Y-308577D01*
X434167Y-308437D01*
X434762Y-308039D01*
X434923D01*
X435518Y-308437D01*
X436221Y-308577D01*
X436923Y-308437D01*
X437518Y-308039D01*
X437545Y-307999D01*
X438045D01*
X438072Y-308039D01*
X438668Y-308437D01*
X439370Y-308577D01*
X440072Y-308437D01*
X440363Y-308243D01*
X440748Y-308075D01*
X441133Y-308243D01*
X441424Y-308437D01*
X442126Y-308577D01*
X442828Y-308437D01*
X443391Y-308061D01*
X443538Y-307999D01*
X443864D01*
X444010Y-308061D01*
X444573Y-308437D01*
X445276Y-308577D01*
X445978Y-308437D01*
X446269Y-308243D01*
X446654Y-308075D01*
X447039Y-308243D01*
X447329Y-308437D01*
X448032Y-308577D01*
X448734Y-308437D01*
X449297Y-308061D01*
X449443Y-307999D01*
X449769D01*
X449916Y-308061D01*
X450479Y-308437D01*
X451181Y-308577D01*
X451883Y-308437D01*
X452479Y-308039D01*
X452639D01*
X453235Y-308437D01*
X453937Y-308577D01*
X454639Y-308437D01*
X455235Y-308039D01*
X455633Y-307444D01*
X455772Y-306742D01*
X455633Y-306039D01*
X455235Y-305444D01*
X454639Y-305046D01*
X453937Y-304907D01*
D02*
G37*
G36*
X470275Y-306474D02*
X469462Y-306635D01*
X468773Y-307096D01*
X468313Y-307785D01*
X468151Y-308597D01*
X468313Y-309410D01*
X468773Y-310099D01*
X469462Y-310560D01*
X470275Y-310721D01*
X471088Y-310560D01*
X471777Y-310099D01*
X472237Y-309410D01*
X472399Y-308597D01*
X472237Y-307785D01*
X471777Y-307096D01*
X471088Y-306635D01*
X470275Y-306474D01*
D02*
G37*
G36*
X391535D02*
X390722Y-306635D01*
X390033Y-307096D01*
X389573Y-307785D01*
X389411Y-308597D01*
X389573Y-309410D01*
X390033Y-310099D01*
X390722Y-310560D01*
X391535Y-310721D01*
X392348Y-310560D01*
X393037Y-310099D01*
X393497Y-309410D01*
X393659Y-308597D01*
X393497Y-307785D01*
X393037Y-307096D01*
X392348Y-306635D01*
X391535Y-306474D01*
D02*
G37*
G36*
X683858Y-308795D02*
X683156Y-308934D01*
X682560Y-309332D01*
X682163Y-309928D01*
X682023Y-310630D01*
X682163Y-311332D01*
X682560Y-311928D01*
X683156Y-312326D01*
X683858Y-312465D01*
X684561Y-312326D01*
X685156Y-311928D01*
X685554Y-311332D01*
X685694Y-310630D01*
X685554Y-309928D01*
X685156Y-309332D01*
X684561Y-308934D01*
X683858Y-308795D01*
D02*
G37*
G36*
X285128Y-301599D02*
X283756Y-301734D01*
X282436Y-302134D01*
X281220Y-302784D01*
X280154Y-303659D01*
X279279Y-304725D01*
X278629Y-305941D01*
X278229Y-307260D01*
X278094Y-308632D01*
X278229Y-310005D01*
X278629Y-311324D01*
X279279Y-312540D01*
X280154Y-313606D01*
X281220Y-314481D01*
X282436Y-315131D01*
X283756Y-315531D01*
X285128Y-315666D01*
X286500Y-315531D01*
X287820Y-315131D01*
X289036Y-314481D01*
X290102Y-313606D01*
X290976Y-312540D01*
X291626Y-311324D01*
X292027Y-310005D01*
X292162Y-308632D01*
X292027Y-307260D01*
X291626Y-305941D01*
X290976Y-304725D01*
X290102Y-303659D01*
X289036Y-302784D01*
X287820Y-302134D01*
X286500Y-301734D01*
X285128Y-301599D01*
D02*
G37*
G36*
X634252Y-312732D02*
X633550Y-312871D01*
X632954Y-313269D01*
X632556Y-313865D01*
X632417Y-314567D01*
X632556Y-315269D01*
X632954Y-315865D01*
X633550Y-316263D01*
X634252Y-316402D01*
X634954Y-316263D01*
X635550Y-315865D01*
X635948Y-315269D01*
X636087Y-314567D01*
X635948Y-313865D01*
X635550Y-313269D01*
X634954Y-312871D01*
X634252Y-312732D01*
D02*
G37*
G36*
X653150Y-312732D02*
X652447Y-312871D01*
X651852Y-313269D01*
X651454Y-313865D01*
X651314Y-314567D01*
X651454Y-315269D01*
X651852Y-315865D01*
X652447Y-316263D01*
X653150Y-316402D01*
X653852Y-316263D01*
X654447Y-315865D01*
X654845Y-315269D01*
X654985Y-314567D01*
X654845Y-313865D01*
X654447Y-313269D01*
X653852Y-312871D01*
X653150Y-312732D01*
D02*
G37*
G36*
X664966Y-314747D02*
X664263Y-314887D01*
X663668Y-315285D01*
X663270Y-315880D01*
X663130Y-316582D01*
X663270Y-317285D01*
X663668Y-317880D01*
X664263Y-318278D01*
X664966Y-318418D01*
X665668Y-318278D01*
X666263Y-317880D01*
X666661Y-317285D01*
X666801Y-316582D01*
X666661Y-315880D01*
X666263Y-315285D01*
X665668Y-314887D01*
X664966Y-314747D01*
D02*
G37*
G36*
X533015Y-305825D02*
X531662Y-305958D01*
X530360Y-306353D01*
X529160Y-306995D01*
X528109Y-307857D01*
X527246Y-308909D01*
X526605Y-310109D01*
X526210Y-311410D01*
X526076Y-312764D01*
X526210Y-314118D01*
X526605Y-315419D01*
X527246Y-316619D01*
X528109Y-317671D01*
X529160Y-318533D01*
X530360Y-319175D01*
X531662Y-319570D01*
X533015Y-319703D01*
X534369Y-319570D01*
X535671Y-319175D01*
X536870Y-318533D01*
X537922Y-317671D01*
X538785Y-316619D01*
X539426Y-315419D01*
X539821Y-314118D01*
X539954Y-312764D01*
X539821Y-311410D01*
X539426Y-310109D01*
X538785Y-308909D01*
X537922Y-307857D01*
X536870Y-306995D01*
X535671Y-306353D01*
X534369Y-305958D01*
X533015Y-305825D01*
D02*
G37*
G36*
X336515D02*
X335162Y-305958D01*
X333860Y-306353D01*
X332660Y-306995D01*
X331609Y-307857D01*
X330746Y-308909D01*
X330105Y-310109D01*
X329710Y-311410D01*
X329576Y-312764D01*
X329710Y-314118D01*
X330105Y-315419D01*
X330746Y-316619D01*
X331609Y-317671D01*
X332660Y-318533D01*
X333860Y-319175D01*
X335162Y-319570D01*
X336515Y-319703D01*
X337869Y-319570D01*
X339171Y-319175D01*
X340370Y-318533D01*
X341422Y-317671D01*
X342285Y-316619D01*
X342926Y-315419D01*
X343321Y-314118D01*
X343454Y-312764D01*
X343321Y-311410D01*
X342926Y-310109D01*
X342285Y-308909D01*
X341422Y-307857D01*
X340370Y-306995D01*
X339171Y-306353D01*
X337869Y-305958D01*
X336515Y-305825D01*
D02*
G37*
G36*
X160020Y-307502D02*
X158647Y-307637D01*
X157328Y-308037D01*
X156112Y-308687D01*
X155046Y-309562D01*
X154171Y-310628D01*
X153521Y-311844D01*
X153121Y-313163D01*
X152986Y-314535D01*
X153121Y-315908D01*
X153521Y-317227D01*
X154171Y-318443D01*
X155046Y-319509D01*
X156112Y-320384D01*
X157328Y-321034D01*
X158647Y-321434D01*
X160020Y-321569D01*
X161392Y-321434D01*
X162711Y-321034D01*
X163927Y-320384D01*
X164993Y-319509D01*
X165868Y-318443D01*
X166518Y-317227D01*
X166918Y-315908D01*
X167053Y-314535D01*
X166918Y-313163D01*
X166518Y-311844D01*
X165868Y-310628D01*
X164993Y-309562D01*
X163927Y-308687D01*
X162711Y-308037D01*
X161392Y-307637D01*
X160020Y-307502D01*
D02*
G37*
G36*
X-3528Y-311844D02*
X-13402D01*
Y-321718D01*
X-3528D01*
Y-311844D01*
D02*
G37*
G36*
X85416Y-315864D02*
X84713Y-316004D01*
X84118Y-316402D01*
X83720Y-316997D01*
X83580Y-317699D01*
X83720Y-318402D01*
X84118Y-318997D01*
X84275Y-319102D01*
X83934Y-319611D01*
X83795Y-320313D01*
X83934Y-321016D01*
X84332Y-321611D01*
X84928Y-322009D01*
X85630Y-322149D01*
X86332Y-322009D01*
X86928Y-321611D01*
X87326Y-321016D01*
X87465Y-320313D01*
X87326Y-319611D01*
X86928Y-319016D01*
X86771Y-318911D01*
X87111Y-318402D01*
X87251Y-317699D01*
X87111Y-316997D01*
X86713Y-316402D01*
X86118Y-316004D01*
X85416Y-315864D01*
D02*
G37*
G36*
X142520Y-310506D02*
X141343Y-310622D01*
X140213Y-310965D01*
X139170Y-311523D01*
X138257Y-312272D01*
X137507Y-313186D01*
X136950Y-314228D01*
X136607Y-315359D01*
X136491Y-316535D01*
X136607Y-317712D01*
X136950Y-318843D01*
X137507Y-319885D01*
X138257Y-320799D01*
X139170Y-321548D01*
X140213Y-322106D01*
X141343Y-322449D01*
X142520Y-322565D01*
X143696Y-322449D01*
X144827Y-322106D01*
X145869Y-321548D01*
X146783Y-320799D01*
X147533Y-319885D01*
X148090Y-318843D01*
X148433Y-317712D01*
X148549Y-316535D01*
X148433Y-315359D01*
X148090Y-314228D01*
X147533Y-313186D01*
X146783Y-312272D01*
X145869Y-311523D01*
X144827Y-310965D01*
X143696Y-310622D01*
X142520Y-310506D01*
D02*
G37*
G36*
X460630Y-323017D02*
X459928Y-323156D01*
X459365Y-323533D01*
X459218Y-323595D01*
X458892D01*
X458745Y-323533D01*
X458183Y-323156D01*
X457480Y-323017D01*
X456778Y-323156D01*
X456183Y-323554D01*
X456009Y-323814D01*
X455408D01*
X455235Y-323554D01*
X454639Y-323156D01*
X453937Y-323017D01*
X453235Y-323156D01*
X452639Y-323554D01*
X452479D01*
X451883Y-323156D01*
X451181Y-323017D01*
X450479Y-323156D01*
X449883Y-323554D01*
X449485Y-324150D01*
X449468Y-324240D01*
X448958D01*
X448940Y-324150D01*
X448542Y-323554D01*
X447946Y-323156D01*
X447244Y-323017D01*
X446542Y-323156D01*
X446251Y-323351D01*
X445866Y-323519D01*
X445481Y-323351D01*
X445190Y-323156D01*
X444488Y-323017D01*
X443786Y-323156D01*
X443190Y-323554D01*
X442793Y-324150D01*
X442775Y-324240D01*
X442265D01*
X442247Y-324150D01*
X441849Y-323554D01*
X441254Y-323156D01*
X440551Y-323017D01*
X439849Y-323156D01*
X439254Y-323554D01*
X439093D01*
X438498Y-323156D01*
X437795Y-323017D01*
X437093Y-323156D01*
X436498Y-323554D01*
X436100Y-324150D01*
X436082Y-324240D01*
X435572D01*
X435554Y-324150D01*
X435156Y-323554D01*
X434561Y-323156D01*
X433858Y-323017D01*
X433156Y-323156D01*
X432561Y-323554D01*
X432400D01*
X431805Y-323156D01*
X431102Y-323017D01*
X430400Y-323156D01*
X429805Y-323554D01*
X429407Y-324150D01*
X429267Y-324852D01*
X429407Y-325554D01*
X429805Y-326150D01*
X430400Y-326548D01*
X431102Y-326687D01*
X431805Y-326548D01*
X432400Y-326150D01*
X432561D01*
X433156Y-326548D01*
X433858Y-326687D01*
X434561Y-326548D01*
X435156Y-326150D01*
X435554Y-325554D01*
X435572Y-325464D01*
X436082D01*
X436100Y-325554D01*
X436498Y-326150D01*
X437093Y-326548D01*
X437795Y-326687D01*
X438498Y-326548D01*
X439093Y-326150D01*
X439254D01*
X439849Y-326548D01*
X440551Y-326687D01*
X441254Y-326548D01*
X441849Y-326150D01*
X442247Y-325554D01*
X442265Y-325464D01*
X442775D01*
X442793Y-325554D01*
X443190Y-326150D01*
X443786Y-326548D01*
X444488Y-326687D01*
X445190Y-326548D01*
X445481Y-326353D01*
X445866Y-326185D01*
X446251Y-326353D01*
X446542Y-326548D01*
X447244Y-326687D01*
X447946Y-326548D01*
X448542Y-326150D01*
X448940Y-325554D01*
X448958Y-325464D01*
X449468D01*
X449485Y-325554D01*
X449883Y-326150D01*
X450479Y-326548D01*
X451181Y-326687D01*
X451883Y-326548D01*
X452479Y-326150D01*
X452639D01*
X453235Y-326548D01*
X453937Y-326687D01*
X454639Y-326548D01*
X455235Y-326150D01*
X455408Y-325890D01*
X456009D01*
X456183Y-326150D01*
X456778Y-326548D01*
X457480Y-326687D01*
X458183Y-326548D01*
X458745Y-326171D01*
X458892Y-326109D01*
X459218D01*
X459365Y-326171D01*
X459928Y-326548D01*
X460630Y-326687D01*
X461332Y-326548D01*
X461928Y-326150D01*
X462325Y-325554D01*
X462465Y-324852D01*
X462325Y-324150D01*
X461928Y-323554D01*
X461332Y-323156D01*
X460630Y-323017D01*
D02*
G37*
G36*
X294094Y-321136D02*
X292918Y-321252D01*
X291787Y-321595D01*
X290745Y-322152D01*
X289831Y-322902D01*
X289082Y-323816D01*
X288524Y-324858D01*
X288439Y-325140D01*
X287939D01*
X287854Y-324858D01*
X287296Y-323816D01*
X286547Y-322902D01*
X285633Y-322152D01*
X284591Y-321595D01*
X283460Y-321252D01*
X282283Y-321136D01*
X281107Y-321252D01*
X279976Y-321595D01*
X278934Y-322152D01*
X278020Y-322902D01*
X277271Y-323816D01*
X276713Y-324858D01*
X276628Y-325140D01*
X276128D01*
X276043Y-324858D01*
X275485Y-323816D01*
X274736Y-322902D01*
X273822Y-322152D01*
X272780Y-321595D01*
X271649Y-321252D01*
X270472Y-321136D01*
X269296Y-321252D01*
X268165Y-321595D01*
X267123Y-322152D01*
X266209Y-322902D01*
X265459Y-323816D01*
X264902Y-324858D01*
X264734Y-325414D01*
X264211D01*
X264042Y-324858D01*
X263485Y-323816D01*
X262736Y-322902D01*
X261822Y-322152D01*
X260780Y-321595D01*
X259649Y-321252D01*
X258472Y-321136D01*
X257296Y-321252D01*
X256165Y-321595D01*
X255123Y-322152D01*
X254209Y-322902D01*
X253460Y-323816D01*
X252902Y-324858D01*
X252734Y-325414D01*
X252211D01*
X252043Y-324858D01*
X251485Y-323816D01*
X250736Y-322902D01*
X249822Y-322152D01*
X248780Y-321595D01*
X247649Y-321252D01*
X246472Y-321136D01*
X245296Y-321252D01*
X244165Y-321595D01*
X243123Y-322152D01*
X242209Y-322902D01*
X241459Y-323816D01*
X240902Y-324858D01*
X240559Y-325989D01*
X240443Y-327165D01*
X240559Y-328342D01*
X240902Y-329473D01*
X241459Y-330515D01*
X242209Y-331429D01*
X243123Y-332178D01*
X244165Y-332735D01*
X245296Y-333079D01*
X246472Y-333194D01*
X247649Y-333079D01*
X248780Y-332735D01*
X249822Y-332178D01*
X250736Y-331429D01*
X251485Y-330515D01*
X252043Y-329473D01*
X252211Y-328917D01*
X252734D01*
X252902Y-329473D01*
X253460Y-330515D01*
X254209Y-331429D01*
X255123Y-332178D01*
X256165Y-332735D01*
X257296Y-333079D01*
X258472Y-333194D01*
X259649Y-333079D01*
X260780Y-332735D01*
X261822Y-332178D01*
X262736Y-331429D01*
X263485Y-330515D01*
X264042Y-329473D01*
X264211Y-328917D01*
X264734D01*
X264902Y-329473D01*
X265459Y-330515D01*
X266209Y-331429D01*
X267123Y-332178D01*
X268165Y-332735D01*
X269296Y-333079D01*
X270472Y-333194D01*
X271649Y-333079D01*
X272780Y-332735D01*
X273822Y-332178D01*
X274736Y-331429D01*
X275485Y-330515D01*
X276043Y-329473D01*
X276128Y-329191D01*
X276628D01*
X276713Y-329473D01*
X277271Y-330515D01*
X278020Y-331429D01*
X278934Y-332178D01*
X279976Y-332735D01*
X281107Y-333079D01*
X282283Y-333194D01*
X283460Y-333079D01*
X284591Y-332735D01*
X285633Y-332178D01*
X286547Y-331429D01*
X287296Y-330515D01*
X287854Y-329473D01*
X287939Y-329191D01*
X288439D01*
X288524Y-329473D01*
X289082Y-330515D01*
X289831Y-331429D01*
X290745Y-332178D01*
X291787Y-332735D01*
X292918Y-333079D01*
X294094Y-333194D01*
X295271Y-333079D01*
X296402Y-332735D01*
X297444Y-332178D01*
X298358Y-331429D01*
X299108Y-330515D01*
X299665Y-329473D01*
X300008Y-328342D01*
X300124Y-327165D01*
X300008Y-325989D01*
X299665Y-324858D01*
X299108Y-323816D01*
X298358Y-322902D01*
X297444Y-322152D01*
X296402Y-321595D01*
X295271Y-321252D01*
X294094Y-321136D01*
D02*
G37*
G36*
X664961Y-324149D02*
X664258Y-324289D01*
X663663Y-324687D01*
X663265Y-325282D01*
X663125Y-325984D01*
X663265Y-326687D01*
X663663Y-327282D01*
X664258Y-327680D01*
X664961Y-327819D01*
X665663Y-327680D01*
X666258Y-327282D01*
X666656Y-326687D01*
X666796Y-325984D01*
X666656Y-325282D01*
X666258Y-324687D01*
X665663Y-324289D01*
X664961Y-324149D01*
D02*
G37*
G36*
X87598Y-327889D02*
X86896Y-328029D01*
X86301Y-328427D01*
X85903Y-329022D01*
X85763Y-329724D01*
X85903Y-330427D01*
X86301Y-331022D01*
X86896Y-331420D01*
X87598Y-331560D01*
X88301Y-331420D01*
X88896Y-331022D01*
X89294Y-330427D01*
X89434Y-329724D01*
X89294Y-329022D01*
X88896Y-328427D01*
X88301Y-328029D01*
X87598Y-327889D01*
D02*
G37*
G36*
X62992D02*
X62290Y-328029D01*
X61694Y-328427D01*
X61297Y-329022D01*
X61157Y-329724D01*
X61297Y-330427D01*
X61694Y-331022D01*
X62290Y-331420D01*
X62992Y-331560D01*
X63694Y-331420D01*
X64290Y-331022D01*
X64688Y-330427D01*
X64827Y-329724D01*
X64688Y-329022D01*
X64290Y-328427D01*
X63694Y-328029D01*
X62992Y-327889D01*
D02*
G37*
G36*
X604291Y-325703D02*
X603169Y-325851D01*
X602123Y-326284D01*
X601225Y-326973D01*
X600536Y-327871D01*
X600103Y-328917D01*
X599955Y-330039D01*
X600103Y-331162D01*
X600536Y-332207D01*
X601225Y-333106D01*
X602123Y-333795D01*
X603169Y-334228D01*
X604291Y-334376D01*
X605414Y-334228D01*
X606460Y-333795D01*
X607358Y-333106D01*
X608047Y-332207D01*
X608480Y-331162D01*
X608628Y-330039D01*
X608480Y-328917D01*
X608047Y-327871D01*
X607358Y-326973D01*
X606460Y-326284D01*
X605414Y-325851D01*
X604291Y-325703D01*
D02*
G37*
G36*
X574291D02*
X573169Y-325851D01*
X572123Y-326284D01*
X571225Y-326973D01*
X570536Y-327871D01*
X570103Y-328917D01*
X569955Y-330039D01*
X570103Y-331162D01*
X570536Y-332207D01*
X571225Y-333106D01*
X572123Y-333795D01*
X573169Y-334228D01*
X574291Y-334376D01*
X575414Y-334228D01*
X576460Y-333795D01*
X577358Y-333106D01*
X578047Y-332207D01*
X578480Y-331162D01*
X578628Y-330039D01*
X578480Y-328917D01*
X578047Y-327871D01*
X577358Y-326973D01*
X576460Y-326284D01*
X575414Y-325851D01*
X574291Y-325703D01*
D02*
G37*
G36*
X87598Y-333795D02*
X86896Y-333934D01*
X86301Y-334332D01*
X85903Y-334928D01*
X85763Y-335630D01*
X85903Y-336332D01*
X86301Y-336928D01*
X86896Y-337326D01*
X87598Y-337465D01*
X88301Y-337326D01*
X88896Y-336928D01*
X89294Y-336332D01*
X89434Y-335630D01*
X89294Y-334928D01*
X88896Y-334332D01*
X88301Y-333934D01*
X87598Y-333795D01*
D02*
G37*
G36*
X508997Y-333840D02*
X508295Y-333979D01*
X507699Y-334377D01*
X507302Y-334973D01*
X507162Y-335675D01*
X507302Y-336377D01*
X507699Y-336973D01*
X508295Y-337370D01*
X508997Y-337510D01*
X509699Y-337370D01*
X510295Y-336973D01*
X510693Y-336377D01*
X510832Y-335675D01*
X510693Y-334973D01*
X510295Y-334377D01*
X509699Y-333979D01*
X508997Y-333840D01*
D02*
G37*
G36*
X74803Y-337732D02*
X74101Y-337871D01*
X73505Y-338269D01*
X73108Y-338865D01*
X72968Y-339567D01*
X73108Y-340269D01*
X73505Y-340865D01*
X74101Y-341263D01*
X74803Y-341402D01*
X75506Y-341263D01*
X76101Y-340865D01*
X76431Y-340370D01*
X76879Y-340541D01*
X76907Y-340559D01*
X77045Y-341253D01*
X77442Y-341849D01*
X78038Y-342247D01*
X78740Y-342386D01*
X79443Y-342247D01*
X80038Y-341849D01*
X80436Y-341253D01*
X80575Y-340551D01*
X80436Y-339849D01*
X80038Y-339253D01*
X79443Y-338856D01*
X78740Y-338716D01*
X78038Y-338856D01*
X77442Y-339253D01*
X77112Y-339748D01*
X76664Y-339577D01*
X76637Y-339559D01*
X76499Y-338865D01*
X76101Y-338269D01*
X75506Y-337871D01*
X74803Y-337732D01*
D02*
G37*
G36*
X142520Y-341078D02*
X141817Y-341218D01*
X141222Y-341616D01*
X140824Y-342211D01*
X140684Y-342913D01*
X140824Y-343616D01*
X141222Y-344211D01*
X141817Y-344609D01*
X142520Y-344749D01*
X143222Y-344609D01*
X143817Y-344211D01*
X144215Y-343616D01*
X144355Y-342913D01*
X144215Y-342211D01*
X143817Y-341616D01*
X143222Y-341218D01*
X142520Y-341078D01*
D02*
G37*
G36*
X-23622Y-333795D02*
X-24324Y-333934D01*
X-24920Y-334332D01*
X-25318Y-334928D01*
X-25457Y-335630D01*
X-25318Y-336332D01*
X-24920Y-336928D01*
X-24324Y-337326D01*
X-24234Y-337344D01*
Y-337853D01*
X-24324Y-337871D01*
X-24920Y-338269D01*
X-25318Y-338865D01*
X-25457Y-339567D01*
X-25318Y-340269D01*
X-25032Y-340696D01*
X-24958Y-341043D01*
X-25032Y-341391D01*
X-25318Y-341817D01*
X-25457Y-342520D01*
X-25318Y-343222D01*
X-24920Y-343817D01*
X-24324Y-344215D01*
X-24234Y-344233D01*
Y-344743D01*
X-24324Y-344761D01*
X-24920Y-345159D01*
X-25318Y-345754D01*
X-25457Y-346457D01*
X-25318Y-347159D01*
X-24920Y-347754D01*
X-24324Y-348152D01*
X-23622Y-348292D01*
X-22920Y-348152D01*
X-22324Y-347754D01*
X-21926Y-347159D01*
X-21787Y-346457D01*
X-21926Y-345754D01*
X-22324Y-345159D01*
X-22920Y-344761D01*
X-23010Y-344743D01*
Y-344233D01*
X-22920Y-344215D01*
X-22324Y-343817D01*
X-21926Y-343222D01*
X-21787Y-342520D01*
X-21926Y-341817D01*
X-22212Y-341391D01*
X-22286Y-341043D01*
X-22212Y-340696D01*
X-21926Y-340269D01*
X-21787Y-339567D01*
X-21926Y-338865D01*
X-22324Y-338269D01*
X-22920Y-337871D01*
X-23010Y-337853D01*
Y-337344D01*
X-22920Y-337326D01*
X-22324Y-336928D01*
X-21926Y-336332D01*
X-21787Y-335630D01*
X-21926Y-334928D01*
X-22324Y-334332D01*
X-22920Y-333934D01*
X-23622Y-333795D01*
D02*
G37*
G36*
X141981Y-345208D02*
X141279Y-345348D01*
X140683Y-345745D01*
X140286Y-346341D01*
X140146Y-347043D01*
X140286Y-347746D01*
X140683Y-348341D01*
X141279Y-348739D01*
X141981Y-348879D01*
X142683Y-348739D01*
X143279Y-348341D01*
X143677Y-347746D01*
X143816Y-347043D01*
X143677Y-346341D01*
X143279Y-345745D01*
X142683Y-345348D01*
X141981Y-345208D01*
D02*
G37*
G36*
X509391Y-348800D02*
X508688Y-348940D01*
X508093Y-349338D01*
X507695Y-349933D01*
X507555Y-350636D01*
X507695Y-351338D01*
X508093Y-351933D01*
X508688Y-352331D01*
X509391Y-352471D01*
X510093Y-352331D01*
X510688Y-351933D01*
X511086Y-351338D01*
X511226Y-350636D01*
X511086Y-349933D01*
X510688Y-349338D01*
X510093Y-348940D01*
X509391Y-348800D01*
D02*
G37*
G36*
X486221Y-327009D02*
X484102Y-327176D01*
X482036Y-327672D01*
X480073Y-328485D01*
X478261Y-329596D01*
X476645Y-330976D01*
X475265Y-332592D01*
X474155Y-334403D01*
X473342Y-336367D01*
X472845Y-338433D01*
X472679Y-340551D01*
X472845Y-342670D01*
X473342Y-344736D01*
X474155Y-346699D01*
X475265Y-348511D01*
X476645Y-350127D01*
X478261Y-351507D01*
X480073Y-352617D01*
X482036Y-353430D01*
X484102Y-353926D01*
X486221Y-354093D01*
X488339Y-353926D01*
X490405Y-353430D01*
X492368Y-352617D01*
X494180Y-351507D01*
X495796Y-350127D01*
X497176Y-348511D01*
X498286Y-346699D01*
X499099Y-344736D01*
X499595Y-342670D01*
X499762Y-340551D01*
X499595Y-338433D01*
X499099Y-336367D01*
X498286Y-334403D01*
X497176Y-332592D01*
X495796Y-330976D01*
X494180Y-329596D01*
X492368Y-328485D01*
X490405Y-327672D01*
X488339Y-327176D01*
X486221Y-327009D01*
D02*
G37*
G36*
X685039Y-327010D02*
X682921Y-327176D01*
X680855Y-327672D01*
X678892Y-328485D01*
X677080Y-329596D01*
X675464Y-330976D01*
X674084Y-332592D01*
X672974Y-334403D01*
X672160Y-336367D01*
X671664Y-338433D01*
X671498Y-340551D01*
X671664Y-342670D01*
X672160Y-344736D01*
X672974Y-346699D01*
X674084Y-348511D01*
X675464Y-350127D01*
X677080Y-351507D01*
X678892Y-352617D01*
X680855Y-353430D01*
X682921Y-353926D01*
X685039Y-354093D01*
X687158Y-353926D01*
X689224Y-353430D01*
X691187Y-352617D01*
X692999Y-351507D01*
X694615Y-350127D01*
X695995Y-348511D01*
X697105Y-346699D01*
X697918Y-344736D01*
X698414Y-342670D01*
X698581Y-340551D01*
X698414Y-338433D01*
X697918Y-336367D01*
X697105Y-334403D01*
X695995Y-332592D01*
X694615Y-330976D01*
X692999Y-329596D01*
X691187Y-328485D01*
X689224Y-327672D01*
X687158Y-327176D01*
X685039Y-327010D01*
D02*
G37*
G36*
X157480Y-356826D02*
X156778Y-356966D01*
X156496Y-357154D01*
X156214Y-356966D01*
X155512Y-356826D01*
X154809Y-356966D01*
X154528Y-357154D01*
X154246Y-356966D01*
X153543Y-356826D01*
X152841Y-356966D01*
X152246Y-357364D01*
X151848Y-357959D01*
X151708Y-358661D01*
X151848Y-359364D01*
X152246Y-359959D01*
X152286Y-359986D01*
Y-360486D01*
X152246Y-360513D01*
X151848Y-361109D01*
X151708Y-361811D01*
X151848Y-362513D01*
X152246Y-363109D01*
X152841Y-363507D01*
X153543Y-363646D01*
X154246Y-363507D01*
X154528Y-363318D01*
X154809Y-363507D01*
X155512Y-363646D01*
X156214Y-363507D01*
X156496Y-363318D01*
X156778Y-363507D01*
X157480Y-363646D01*
X158183Y-363507D01*
X158778Y-363109D01*
X159176Y-362513D01*
X159316Y-361811D01*
X159176Y-361109D01*
X158778Y-360513D01*
X158738Y-360486D01*
Y-359986D01*
X158778Y-359959D01*
X159176Y-359364D01*
X159316Y-358661D01*
X159176Y-357959D01*
X158778Y-357364D01*
X158183Y-356966D01*
X157480Y-356826D01*
D02*
G37*
G36*
X198392Y-365007D02*
X197690Y-365146D01*
X197094Y-365544D01*
X196697Y-366140D01*
X196557Y-366842D01*
X196697Y-367544D01*
X197094Y-368140D01*
X197343Y-368306D01*
X197148Y-368777D01*
X196701Y-368688D01*
X195999Y-368828D01*
X195403Y-369225D01*
X195005Y-369821D01*
X194866Y-370523D01*
X195005Y-371225D01*
X195403Y-371821D01*
X195999Y-372219D01*
X196701Y-372358D01*
X197403Y-372219D01*
X197998Y-371821D01*
X198396Y-371225D01*
X198536Y-370523D01*
X198396Y-369821D01*
X197998Y-369225D01*
X197750Y-369059D01*
X197945Y-368588D01*
X198392Y-368677D01*
X199094Y-368537D01*
X199690Y-368140D01*
X200088Y-367544D01*
X200227Y-366842D01*
X200088Y-366140D01*
X199690Y-365544D01*
X199094Y-365146D01*
X198392Y-365007D01*
D02*
G37*
G36*
X241929Y-372820D02*
X241227Y-372960D01*
X240631Y-373357D01*
X240234Y-373953D01*
X240215Y-374043D01*
X239706D01*
X239688Y-373953D01*
X239290Y-373357D01*
X238695Y-372960D01*
X237992Y-372820D01*
X237290Y-372960D01*
X236694Y-373357D01*
X236297Y-373953D01*
X236157Y-374655D01*
X236297Y-375357D01*
X236694Y-375953D01*
X237290Y-376351D01*
X237992Y-376490D01*
X238695Y-376351D01*
X239290Y-375953D01*
X239688Y-375357D01*
X239706Y-375267D01*
X240215D01*
X240234Y-375357D01*
X240631Y-375953D01*
X241227Y-376351D01*
X241929Y-376490D01*
X242632Y-376351D01*
X243227Y-375953D01*
X243625Y-375357D01*
X243764Y-374655D01*
X243625Y-373953D01*
X243227Y-373357D01*
X242632Y-372960D01*
X241929Y-372820D01*
D02*
G37*
G36*
X210433D02*
X209731Y-372960D01*
X209135Y-373357D01*
X208737Y-373953D01*
X208719Y-374043D01*
X208210D01*
X208192Y-373953D01*
X207794Y-373357D01*
X207198Y-372960D01*
X206496Y-372820D01*
X205794Y-372960D01*
X205198Y-373357D01*
X204801Y-373953D01*
X204661Y-374655D01*
X204801Y-375357D01*
X205198Y-375953D01*
X205794Y-376351D01*
X206496Y-376490D01*
X207198Y-376351D01*
X207794Y-375953D01*
X208192Y-375357D01*
X208210Y-375267D01*
X208719D01*
X208737Y-375357D01*
X209135Y-375953D01*
X209731Y-376351D01*
X210433Y-376490D01*
X211135Y-376351D01*
X211731Y-375953D01*
X212129Y-375357D01*
X212268Y-374655D01*
X212129Y-373953D01*
X211731Y-373357D01*
X211135Y-372960D01*
X210433Y-372820D01*
D02*
G37*
G36*
X218445Y-372272D02*
X217743Y-372412D01*
X217147Y-372810D01*
X216749Y-373405D01*
X216610Y-374108D01*
X216749Y-374810D01*
X217147Y-375405D01*
X217743Y-375803D01*
X218445Y-375943D01*
X219147Y-375803D01*
X219743Y-375405D01*
X220141Y-374810D01*
X220280Y-374108D01*
X220141Y-373405D01*
X219743Y-372810D01*
X219147Y-372412D01*
X218445Y-372272D01*
D02*
G37*
G36*
X269502Y-372456D02*
X268800Y-372595D01*
X268205Y-372993D01*
X267807Y-373589D01*
X267667Y-374291D01*
X267807Y-374993D01*
X268205Y-375589D01*
X268800Y-375987D01*
X269502Y-376126D01*
X270205Y-375987D01*
X270800Y-375589D01*
X271159Y-375051D01*
X271393Y-375038D01*
X271679Y-375104D01*
X271730Y-375357D01*
X272128Y-375953D01*
X272723Y-376351D01*
X273425Y-376490D01*
X274128Y-376351D01*
X274723Y-375953D01*
X275121Y-375357D01*
X275260Y-374655D01*
X275121Y-373953D01*
X274723Y-373357D01*
X274128Y-372960D01*
X273425Y-372820D01*
X272723Y-372960D01*
X272128Y-373357D01*
X271769Y-373895D01*
X271535Y-373908D01*
X271248Y-373842D01*
X271198Y-373589D01*
X270800Y-372993D01*
X270205Y-372595D01*
X269502Y-372456D01*
D02*
G37*
G36*
X253655Y-372586D02*
X252953Y-372726D01*
X252357Y-373123D01*
X251959Y-373719D01*
X251820Y-374421D01*
X251959Y-375123D01*
X252357Y-375719D01*
X252953Y-376117D01*
X253655Y-376256D01*
X254357Y-376117D01*
X254953Y-375719D01*
X255436D01*
X255592Y-375953D01*
X256187Y-376351D01*
X256890Y-376490D01*
X257592Y-376351D01*
X258188Y-375953D01*
X258585Y-375357D01*
X258725Y-374655D01*
X258585Y-373953D01*
X258188Y-373357D01*
X257592Y-372960D01*
X256890Y-372820D01*
X256187Y-372960D01*
X255592Y-373357D01*
X255109D01*
X254953Y-373123D01*
X254357Y-372726D01*
X253655Y-372586D01*
D02*
G37*
G36*
X222638Y-372820D02*
X221936Y-372960D01*
X221340Y-373357D01*
X220942Y-373953D01*
X220802Y-374655D01*
X220942Y-375357D01*
X221340Y-375953D01*
X221936Y-376351D01*
X222638Y-376490D01*
X223340Y-376351D01*
X223936Y-375953D01*
X224333Y-375357D01*
X224473Y-374655D01*
X224333Y-373953D01*
X223936Y-373357D01*
X223340Y-372960D01*
X222638Y-372820D01*
D02*
G37*
G36*
X190354Y-375576D02*
X189652Y-375715D01*
X189057Y-376113D01*
X188659Y-376709D01*
X188519Y-377411D01*
X188659Y-378113D01*
X189057Y-378709D01*
X189652Y-379107D01*
X190354Y-379246D01*
X191057Y-379107D01*
X191652Y-378709D01*
X192050Y-378113D01*
X192190Y-377411D01*
X192050Y-376709D01*
X191652Y-376113D01*
X191057Y-375715D01*
X190354Y-375576D01*
D02*
G37*
G36*
X178543D02*
X177841Y-375715D01*
X177246Y-376113D01*
X176848Y-376709D01*
X176708Y-377411D01*
X176848Y-378113D01*
X177246Y-378709D01*
X177841Y-379107D01*
X178543Y-379246D01*
X179246Y-379107D01*
X179841Y-378709D01*
X180239Y-378113D01*
X180379Y-377411D01*
X180239Y-376709D01*
X179841Y-376113D01*
X179246Y-375715D01*
X178543Y-375576D01*
D02*
G37*
G36*
X158661Y-384631D02*
X157959Y-384771D01*
X157677Y-384959D01*
X157395Y-384771D01*
X156693Y-384631D01*
X155991Y-384771D01*
X155709Y-384959D01*
X155427Y-384771D01*
X154724Y-384631D01*
X154022Y-384771D01*
X153427Y-385168D01*
X153029Y-385764D01*
X152889Y-386466D01*
X153029Y-387169D01*
X153427Y-387764D01*
X153467Y-387791D01*
Y-388291D01*
X153427Y-388318D01*
X153029Y-388913D01*
X152889Y-389616D01*
X153029Y-390318D01*
X153427Y-390914D01*
X154022Y-391311D01*
X154724Y-391451D01*
X155427Y-391311D01*
X155709Y-391123D01*
X155991Y-391311D01*
X156693Y-391451D01*
X157395Y-391311D01*
X157677Y-391123D01*
X157959Y-391311D01*
X158661Y-391451D01*
X159364Y-391311D01*
X159959Y-390914D01*
X160357Y-390318D01*
X160497Y-389616D01*
X160357Y-388913D01*
X159959Y-388318D01*
X159919Y-388291D01*
Y-387791D01*
X159959Y-387764D01*
X160357Y-387169D01*
X160497Y-386466D01*
X160357Y-385764D01*
X159959Y-385168D01*
X159364Y-384771D01*
X158661Y-384631D01*
D02*
G37*
G36*
X186614D02*
X185912Y-384771D01*
X185317Y-385168D01*
X184919Y-385764D01*
X184901Y-385855D01*
X184391D01*
X184373Y-385764D01*
X183975Y-385168D01*
X183379Y-384771D01*
X182677Y-384631D01*
X181975Y-384771D01*
X181379Y-385168D01*
X181206Y-385428D01*
X180605D01*
X180432Y-385168D01*
X179836Y-384771D01*
X179134Y-384631D01*
X178431Y-384771D01*
X177836Y-385168D01*
X177438Y-385764D01*
X177299Y-386466D01*
X177438Y-387169D01*
X177836Y-387764D01*
X177877Y-387791D01*
Y-388291D01*
X177836Y-388318D01*
X177438Y-388913D01*
X177299Y-389616D01*
X177438Y-390318D01*
X177836Y-390914D01*
X178431Y-391311D01*
X179134Y-391451D01*
X179836Y-391311D01*
X180432Y-390914D01*
X180605Y-390654D01*
X181206D01*
X181379Y-390914D01*
X181975Y-391311D01*
X182677Y-391451D01*
X183379Y-391311D01*
X183975Y-390914D01*
X184373Y-390318D01*
X184391Y-390227D01*
X184901D01*
X184919Y-390318D01*
X185317Y-390914D01*
X185912Y-391311D01*
X186614Y-391451D01*
X187317Y-391311D01*
X187912Y-390914D01*
X188310Y-390318D01*
X188449Y-389616D01*
X188310Y-388913D01*
X187912Y-388318D01*
X187871Y-388291D01*
Y-387791D01*
X187912Y-387764D01*
X188310Y-387169D01*
X188449Y-386466D01*
X188310Y-385764D01*
X187912Y-385168D01*
X187317Y-384771D01*
X186614Y-384631D01*
D02*
G37*
G36*
X232480Y-385418D02*
X231778Y-385558D01*
X231215Y-385934D01*
X231069Y-385996D01*
X230743D01*
X230596Y-385934D01*
X230033Y-385558D01*
X229331Y-385418D01*
X228628Y-385558D01*
X228033Y-385956D01*
X227635Y-386551D01*
X227496Y-387253D01*
X227635Y-387956D01*
X228033Y-388551D01*
X228628Y-388949D01*
X229331Y-389089D01*
X230033Y-388949D01*
X230596Y-388573D01*
X230743Y-388511D01*
X231069D01*
X231215Y-388573D01*
X231778Y-388949D01*
X232480Y-389089D01*
X233183Y-388949D01*
X233778Y-388551D01*
X234176Y-387956D01*
X234316Y-387253D01*
X234176Y-386551D01*
X233778Y-385956D01*
X233183Y-385558D01*
X232480Y-385418D01*
D02*
G37*
G36*
X215945D02*
X215243Y-385558D01*
X214680Y-385934D01*
X214533Y-385996D01*
X214207D01*
X214060Y-385934D01*
X213498Y-385558D01*
X212795Y-385418D01*
X212093Y-385558D01*
X211498Y-385956D01*
X211100Y-386551D01*
X210960Y-387253D01*
X211100Y-387956D01*
X211498Y-388551D01*
X212093Y-388949D01*
X212795Y-389089D01*
X213498Y-388949D01*
X214060Y-388573D01*
X214207Y-388511D01*
X214533D01*
X214680Y-388573D01*
X215243Y-388949D01*
X215945Y-389089D01*
X216647Y-388949D01*
X217243Y-388551D01*
X217640Y-387956D01*
X217780Y-387253D01*
X217640Y-386551D01*
X217243Y-385956D01*
X216647Y-385558D01*
X215945Y-385418D01*
D02*
G37*
G36*
X265158D02*
X264455Y-385558D01*
X263890Y-385935D01*
X263746Y-385999D01*
X263331D01*
X263304Y-385958D01*
X262708Y-385560D01*
X262006Y-385420D01*
X261304Y-385560D01*
X260708Y-385958D01*
X260311Y-386553D01*
X260171Y-387255D01*
X260311Y-387958D01*
X260708Y-388553D01*
X261304Y-388951D01*
X262006Y-389090D01*
X262708Y-388951D01*
X263273Y-388574D01*
X263417Y-388510D01*
X263832D01*
X263860Y-388551D01*
X264455Y-388949D01*
X265158Y-389089D01*
X265860Y-388949D01*
X266455Y-388551D01*
X266853Y-387956D01*
X266993Y-387253D01*
X266853Y-386551D01*
X266455Y-385956D01*
X265860Y-385558D01*
X265158Y-385418D01*
D02*
G37*
G36*
X246339Y-385140D02*
X245636Y-385279D01*
X245041Y-385677D01*
X244643Y-386273D01*
X244503Y-386975D01*
X244643Y-387677D01*
X245041Y-388273D01*
X245636Y-388671D01*
X246339Y-388810D01*
X247041Y-388671D01*
X247476Y-388380D01*
X248059Y-388472D01*
X248112Y-388551D01*
X248707Y-388949D01*
X249410Y-389089D01*
X250112Y-388949D01*
X250707Y-388551D01*
X251105Y-387956D01*
X251245Y-387253D01*
X251105Y-386551D01*
X250707Y-385956D01*
X250112Y-385558D01*
X249410Y-385418D01*
X248707Y-385558D01*
X248327Y-385812D01*
X247689Y-385756D01*
X247636Y-385677D01*
X247041Y-385279D01*
X246339Y-385140D01*
D02*
G37*
G36*
X0Y-364854D02*
X-2118Y-365020D01*
X-4185Y-365516D01*
X-6148Y-366330D01*
X-7960Y-367440D01*
X-9575Y-368820D01*
X-10955Y-370436D01*
X-12066Y-372248D01*
X-12879Y-374211D01*
X-13375Y-376277D01*
X-13542Y-378395D01*
X-13375Y-380514D01*
X-12879Y-382580D01*
X-12066Y-384543D01*
X-10955Y-386355D01*
X-9575Y-387971D01*
X-7960Y-389351D01*
X-6148Y-390461D01*
X-4185Y-391274D01*
X-2118Y-391770D01*
X0Y-391937D01*
X2118Y-391770D01*
X4185Y-391274D01*
X6148Y-390461D01*
X7960Y-389351D01*
X9576Y-387971D01*
X10955Y-386355D01*
X12066Y-384543D01*
X12879Y-382580D01*
X13375Y-380514D01*
X13542Y-378395D01*
X13375Y-376277D01*
X12879Y-374211D01*
X12066Y-372248D01*
X10955Y-370436D01*
X9576Y-368820D01*
X7960Y-367440D01*
X6148Y-366330D01*
X4185Y-365516D01*
X2118Y-365020D01*
X0Y-364854D01*
D02*
G37*
%LPD*%
D212*
X695866Y-105610D02*
D03*
Y-72342D02*
D03*
X688976D02*
D03*
Y-105610D02*
D03*
D213*
X682283Y-74803D02*
D03*
Y-103150D02*
D03*
D215*
X643701Y-127445D02*
D03*
D216*
Y-143945D02*
D03*
D240*
X171496Y-120079D02*
D03*
D241*
X142520Y-236614D02*
D03*
X302362Y-316535D02*
D03*
D03*
X142520Y-236614D02*
D03*
D245*
X-18464Y-326781D02*
D03*
X1535D02*
D03*
Y-306781D02*
D03*
X-18464D02*
D03*
X-18465Y-273630D02*
D03*
X1535D02*
D03*
Y-253630D02*
D03*
X-18465D02*
D03*
Y-220480D02*
D03*
X1535D02*
D03*
Y-200480D02*
D03*
X-18465D02*
D03*
X-18464Y-167332D02*
D03*
X1535D02*
D03*
Y-147332D02*
D03*
X-18464D02*
D03*
D248*
X549055Y13937D02*
D03*
Y3937D02*
D03*
D250*
X84079Y-105653D02*
D03*
X62499Y-117255D02*
D03*
X585433Y-114961D02*
D03*
X584252Y-117717D02*
D03*
X555512Y-218504D02*
D03*
X430492Y-136473D02*
D03*
X414567Y-137402D02*
D03*
X692037Y-315878D02*
D03*
X692126Y-322441D02*
D03*
X248425Y-129134D02*
D03*
X241077Y-118805D02*
D03*
X255512Y-121260D02*
D03*
X253713Y-109190D02*
D03*
X267717Y-123622D02*
D03*
X267323Y-132677D02*
D03*
X272047Y-131496D02*
D03*
X244664Y-106952D02*
D03*
X609055Y-92520D02*
D03*
X629134Y-102756D02*
D03*
X631814Y-83784D02*
D03*
X629101Y-90137D02*
D03*
X616535Y-84646D02*
D03*
X616929Y-100000D02*
D03*
X569291Y-91339D02*
D03*
X584763Y-100116D02*
D03*
X588976Y-86221D02*
D03*
X600394Y-87795D02*
D03*
X666929Y-98032D02*
D03*
X662539Y-107066D02*
D03*
X696762Y-63288D02*
D03*
X685716Y-22157D02*
D03*
X679517Y-26553D02*
D03*
X693915Y-33393D02*
D03*
X686728Y-33442D02*
D03*
X675926Y-72691D02*
D03*
X660719Y-75726D02*
D03*
X694095Y-62205D02*
D03*
X693977Y-53201D02*
D03*
X676378Y-83858D02*
D03*
X569092Y-108048D02*
D03*
X546386Y-109024D02*
D03*
X548093Y-185219D02*
D03*
X548425Y-181890D02*
D03*
X548819Y-178740D02*
D03*
X547244Y-157087D02*
D03*
Y-144488D02*
D03*
X524409Y-135827D02*
D03*
X531801Y-127495D02*
D03*
X639764Y-283858D02*
D03*
X554724Y-294882D02*
D03*
X680709Y-212205D02*
D03*
X673622Y-213779D02*
D03*
X669685D02*
D03*
X666142Y-212992D02*
D03*
X599564Y-178940D02*
D03*
X594882Y-179134D02*
D03*
X589764D02*
D03*
X584646Y-178740D02*
D03*
X635827Y-187795D02*
D03*
X635433Y-184252D02*
D03*
X652756Y-164961D02*
D03*
X657480Y-164567D02*
D03*
X662992Y-164961D02*
D03*
X668504D02*
D03*
X681496Y-179528D02*
D03*
X677165Y-172441D02*
D03*
X673228D02*
D03*
X650000Y-231102D02*
D03*
X646434Y-231245D02*
D03*
X570079Y-200000D02*
D03*
X600000Y-248425D02*
D03*
X616535Y-255512D02*
D03*
X612205Y-251575D02*
D03*
X624803Y-255906D02*
D03*
Y-251575D02*
D03*
X624409Y-248031D02*
D03*
X611417Y-247638D02*
D03*
X605118Y-244488D02*
D03*
X673228Y-251181D02*
D03*
X672835Y-257087D02*
D03*
X673622Y-261417D02*
D03*
X676378Y-266142D02*
D03*
X676772Y-270866D02*
D03*
X671260Y-274803D02*
D03*
Y-278740D02*
D03*
X671654Y-283071D02*
D03*
X683716Y-298538D02*
D03*
X637795Y-297638D02*
D03*
X559842Y-257087D02*
D03*
X579134Y-195276D02*
D03*
X574803D02*
D03*
X577953Y-198819D02*
D03*
X590158Y-226378D02*
D03*
X586221Y-226772D02*
D03*
X579921Y-227559D02*
D03*
X576772Y-228740D02*
D03*
X586537Y-234843D02*
D03*
X546850Y-213779D02*
D03*
X548819Y-196063D02*
D03*
X554724Y-207874D02*
D03*
X571162Y-284136D02*
D03*
X577953Y-284646D02*
D03*
X574803Y-284252D02*
D03*
X568110D02*
D03*
X567717Y-259055D02*
D03*
X566535Y-255906D02*
D03*
X570079D02*
D03*
X548425Y-253543D02*
D03*
X545669Y-253937D02*
D03*
X545128Y-280872D02*
D03*
X545276Y-294094D02*
D03*
X544488Y-265748D02*
D03*
X595276Y-291732D02*
D03*
X488583Y-132283D02*
D03*
X506299Y-129921D02*
D03*
X506207Y-127333D02*
D03*
X501669Y-116601D02*
D03*
X500313Y-105734D02*
D03*
X476772Y-123622D02*
D03*
X470472Y-123622D02*
D03*
X444507Y-309009D02*
D03*
X448819Y-309055D02*
D03*
X457480Y-306693D02*
D03*
X451575Y-309055D02*
D03*
X437048Y-308863D02*
D03*
X431102Y-308268D02*
D03*
X461811Y-327165D02*
D03*
X456693D02*
D03*
X454724D02*
D03*
X450394D02*
D03*
X448032D02*
D03*
X443701D02*
D03*
X441732D02*
D03*
X436614D02*
D03*
X429528Y-326772D02*
D03*
X434646Y-327559D02*
D03*
X623622Y-70866D02*
D03*
X43701Y-29921D02*
D03*
X55905Y-31496D02*
D03*
X111024Y-33071D02*
D03*
X125591Y-32283D02*
D03*
X101181Y-18504D02*
D03*
X670079Y-9449D02*
D03*
X673228Y-29528D02*
D03*
X671654Y-62598D02*
D03*
Y-41339D02*
D03*
X596063Y-53937D02*
D03*
X602756Y-39764D02*
D03*
X315097Y-235081D02*
D03*
X287941Y-241819D02*
D03*
X288189Y-235827D02*
D03*
X615748Y-305512D02*
D03*
X562598Y-306693D02*
D03*
X531496Y-262647D02*
D03*
X461811Y-310679D02*
D03*
X450000Y-293750D02*
D03*
X422441Y-293789D02*
D03*
X531496Y-213435D02*
D03*
X338525Y-243567D02*
D03*
X525591Y-233088D02*
D03*
X439697Y-162549D02*
D03*
X343144Y-225173D02*
D03*
X420669Y-157923D02*
D03*
X531496Y-223277D02*
D03*
X338583Y-235236D02*
D03*
X525591Y-242962D02*
D03*
X430150Y-162253D02*
D03*
X343444Y-215373D02*
D03*
X432283Y-293750D02*
D03*
X410528Y-157923D02*
D03*
X342944Y-264473D02*
D03*
X444095Y-293750D02*
D03*
X422835Y-311072D02*
D03*
X531496Y-233088D02*
D03*
X430150Y-157923D02*
D03*
X338444Y-225173D02*
D03*
X402756Y-311072D02*
D03*
X525591Y-253969D02*
D03*
X420079Y-162549D02*
D03*
X343403Y-205651D02*
D03*
X525591Y-203592D02*
D03*
X400295Y-157824D02*
D03*
X343144Y-254773D02*
D03*
X431928Y-311189D02*
D03*
X531496Y-242962D02*
D03*
X338844Y-215273D02*
D03*
X402362Y-293750D02*
D03*
X525591Y-262647D02*
D03*
X410913Y-162758D02*
D03*
X338444Y-264473D02*
D03*
X456299Y-293750D02*
D03*
X437795Y-293750D02*
D03*
X525591Y-213435D02*
D03*
X459319Y-162510D02*
D03*
Y-157922D02*
D03*
X342744Y-243747D02*
D03*
X412598Y-311072D02*
D03*
X531496Y-253969D02*
D03*
X449803Y-157923D02*
D03*
X338744Y-205473D02*
D03*
X531496Y-203592D02*
D03*
X401279Y-162509D02*
D03*
X439961Y-157923D02*
D03*
X338444Y-254773D02*
D03*
X461417Y-293750D02*
D03*
X525591Y-223277D02*
D03*
X449508Y-162549D02*
D03*
X343504Y-235236D02*
D03*
X412205Y-293750D02*
D03*
X639750Y-314581D02*
D03*
X658647Y-314581D02*
D03*
X509405Y-345138D02*
D03*
X509011Y-330177D02*
D03*
X56441Y-143600D02*
D03*
Y-151600D02*
D03*
Y-191600D02*
D03*
Y-199600D02*
D03*
Y-215600D02*
D03*
Y-223600D02*
D03*
Y-231600D02*
D03*
Y-247600D02*
D03*
Y-255600D02*
D03*
Y-271600D02*
D03*
Y-279600D02*
D03*
Y-287600D02*
D03*
Y-303600D02*
D03*
Y-311600D02*
D03*
Y-327600D02*
D03*
Y-335600D02*
D03*
Y-343600D02*
D03*
Y-351600D02*
D03*
X54441Y-139600D02*
D03*
X52441Y-143600D02*
D03*
X54441Y-147600D02*
D03*
X52441Y-151600D02*
D03*
Y-191600D02*
D03*
X54441Y-195600D02*
D03*
X52441Y-199600D02*
D03*
X54441Y-203600D02*
D03*
X52441Y-215600D02*
D03*
X54441Y-219600D02*
D03*
X52441Y-223600D02*
D03*
X54441Y-227600D02*
D03*
X52441Y-231600D02*
D03*
X54441Y-235600D02*
D03*
Y-243600D02*
D03*
X52441Y-247600D02*
D03*
X54441Y-251600D02*
D03*
X52441Y-255600D02*
D03*
X54441Y-267600D02*
D03*
X52441Y-271600D02*
D03*
X54441Y-275600D02*
D03*
X52441Y-279600D02*
D03*
Y-287600D02*
D03*
X54441Y-291600D02*
D03*
Y-299600D02*
D03*
X52441Y-303600D02*
D03*
X54441Y-307600D02*
D03*
X52441Y-311600D02*
D03*
X54441Y-323600D02*
D03*
X52441Y-327600D02*
D03*
X54441Y-331600D02*
D03*
X52441Y-335600D02*
D03*
X54441Y-339600D02*
D03*
X52441Y-343600D02*
D03*
Y-351600D02*
D03*
X50441Y-139600D02*
D03*
X48441Y-143600D02*
D03*
X50441Y-195600D02*
D03*
X48441Y-199600D02*
D03*
Y-223600D02*
D03*
X50441Y-227600D02*
D03*
X48441Y-231600D02*
D03*
X50441Y-235600D02*
D03*
Y-243600D02*
D03*
X48441Y-247600D02*
D03*
X50441Y-251600D02*
D03*
Y-275600D02*
D03*
X48441Y-279600D02*
D03*
Y-287600D02*
D03*
X50441Y-291600D02*
D03*
Y-299600D02*
D03*
X48441Y-303600D02*
D03*
X50441Y-331600D02*
D03*
X48441Y-335600D02*
D03*
X50441Y-339600D02*
D03*
X48441Y-343600D02*
D03*
Y-351600D02*
D03*
X46441Y-139600D02*
D03*
X44441Y-143600D02*
D03*
X46441Y-227600D02*
D03*
X44441Y-231600D02*
D03*
X46441Y-235600D02*
D03*
Y-243600D02*
D03*
X44441Y-247600D02*
D03*
Y-279600D02*
D03*
Y-287600D02*
D03*
X46441Y-291600D02*
D03*
Y-299600D02*
D03*
Y-331600D02*
D03*
X44441Y-335600D02*
D03*
X46441Y-339600D02*
D03*
X44441Y-343600D02*
D03*
Y-351600D02*
D03*
X42441Y-139600D02*
D03*
X40441Y-143600D02*
D03*
Y-223600D02*
D03*
X42441Y-227600D02*
D03*
X40441Y-231600D02*
D03*
X42441Y-235600D02*
D03*
Y-243600D02*
D03*
X40441Y-247600D02*
D03*
X42441Y-299600D02*
D03*
Y-331600D02*
D03*
X40441Y-335600D02*
D03*
X42441Y-339600D02*
D03*
X40441Y-343600D02*
D03*
Y-351600D02*
D03*
X38441Y-139600D02*
D03*
X36441Y-143600D02*
D03*
Y-151600D02*
D03*
Y-215600D02*
D03*
Y-223600D02*
D03*
X38441Y-227600D02*
D03*
X36441Y-231600D02*
D03*
X38441Y-235600D02*
D03*
Y-243600D02*
D03*
X36441Y-247600D02*
D03*
X38441Y-251600D02*
D03*
X36441Y-255600D02*
D03*
Y-327600D02*
D03*
X38441Y-331600D02*
D03*
X36441Y-335600D02*
D03*
X38441Y-339600D02*
D03*
X36441Y-343600D02*
D03*
Y-351600D02*
D03*
X34441Y-139600D02*
D03*
X32441Y-143600D02*
D03*
X34441Y-147600D02*
D03*
X32441Y-151600D02*
D03*
X34441Y-163600D02*
D03*
Y-219600D02*
D03*
Y-227600D02*
D03*
Y-235600D02*
D03*
Y-243600D02*
D03*
Y-251600D02*
D03*
Y-267600D02*
D03*
Y-275600D02*
D03*
Y-299600D02*
D03*
Y-307600D02*
D03*
Y-323600D02*
D03*
X32441Y-327600D02*
D03*
X34441Y-331600D02*
D03*
X32441Y-335600D02*
D03*
X34441Y-339600D02*
D03*
X32441Y-343600D02*
D03*
Y-351600D02*
D03*
X30441Y-139600D02*
D03*
X28441Y-143600D02*
D03*
X30441Y-147600D02*
D03*
X28441Y-151600D02*
D03*
X30441Y-163600D02*
D03*
X28441Y-167600D02*
D03*
Y-327600D02*
D03*
X30441Y-331600D02*
D03*
X28441Y-335600D02*
D03*
X30441Y-339600D02*
D03*
X28441Y-343600D02*
D03*
Y-351600D02*
D03*
X26441Y-139600D02*
D03*
X24441Y-143600D02*
D03*
X26441Y-147600D02*
D03*
X24441Y-151600D02*
D03*
X26441Y-163600D02*
D03*
X24441Y-167600D02*
D03*
Y-191600D02*
D03*
X26441Y-195600D02*
D03*
X24441Y-287600D02*
D03*
X26441Y-299600D02*
D03*
X24441Y-303600D02*
D03*
X26441Y-307600D02*
D03*
X24441Y-311600D02*
D03*
X26441Y-331600D02*
D03*
X24441Y-335600D02*
D03*
X26441Y-339600D02*
D03*
X24441Y-343600D02*
D03*
Y-351600D02*
D03*
X22441Y-139600D02*
D03*
X20441Y-143600D02*
D03*
X22441Y-147600D02*
D03*
X20441Y-151600D02*
D03*
X22441Y-163600D02*
D03*
X20441Y-167600D02*
D03*
X22441Y-171600D02*
D03*
X20441Y-191600D02*
D03*
X22441Y-195600D02*
D03*
X20441Y-199600D02*
D03*
Y-231600D02*
D03*
X22441Y-235600D02*
D03*
Y-243600D02*
D03*
X20441Y-247600D02*
D03*
X22441Y-251600D02*
D03*
X20441Y-255600D02*
D03*
X22441Y-259600D02*
D03*
Y-267600D02*
D03*
X20441Y-271600D02*
D03*
X22441Y-283600D02*
D03*
X20441Y-287600D02*
D03*
X22441Y-291600D02*
D03*
Y-299600D02*
D03*
X20441Y-303600D02*
D03*
X22441Y-307600D02*
D03*
X20441Y-311600D02*
D03*
X22441Y-323600D02*
D03*
X20441Y-335600D02*
D03*
X22441Y-339600D02*
D03*
X20441Y-343600D02*
D03*
Y-351600D02*
D03*
X18441Y-139600D02*
D03*
X16441Y-143600D02*
D03*
X18441Y-147600D02*
D03*
X16441Y-151600D02*
D03*
X18441Y-163600D02*
D03*
X16441Y-167600D02*
D03*
X18441Y-171600D02*
D03*
X16441Y-191600D02*
D03*
X18441Y-195600D02*
D03*
X16441Y-199600D02*
D03*
X18441Y-203600D02*
D03*
X16441Y-215600D02*
D03*
X18441Y-219600D02*
D03*
X16441Y-223600D02*
D03*
X18441Y-235600D02*
D03*
Y-243600D02*
D03*
X16441Y-247600D02*
D03*
X18441Y-251600D02*
D03*
X16441Y-255600D02*
D03*
X18441Y-259600D02*
D03*
Y-267600D02*
D03*
X16441Y-271600D02*
D03*
X18441Y-275600D02*
D03*
X16441Y-279600D02*
D03*
X18441Y-291600D02*
D03*
Y-299600D02*
D03*
X16441Y-303600D02*
D03*
X18441Y-307600D02*
D03*
X16441Y-311600D02*
D03*
X18441Y-323600D02*
D03*
X16441Y-327600D02*
D03*
X18441Y-339600D02*
D03*
X16441Y-343600D02*
D03*
Y-351600D02*
D03*
X14441Y-139600D02*
D03*
X12441Y-143600D02*
D03*
X14441Y-147600D02*
D03*
X12441Y-151600D02*
D03*
X14441Y-163600D02*
D03*
X12441Y-167600D02*
D03*
X14441Y-171600D02*
D03*
X12441Y-191600D02*
D03*
X14441Y-195600D02*
D03*
X12441Y-199600D02*
D03*
X14441Y-203600D02*
D03*
X12441Y-215600D02*
D03*
X14441Y-219600D02*
D03*
X12441Y-223600D02*
D03*
X14441Y-243600D02*
D03*
X12441Y-247600D02*
D03*
X14441Y-251600D02*
D03*
X12441Y-255600D02*
D03*
X14441Y-259600D02*
D03*
Y-267600D02*
D03*
X12441Y-271600D02*
D03*
X14441Y-275600D02*
D03*
X12441Y-279600D02*
D03*
X14441Y-291600D02*
D03*
Y-299600D02*
D03*
X12441Y-303600D02*
D03*
X14441Y-307600D02*
D03*
X12441Y-311600D02*
D03*
X14441Y-323600D02*
D03*
X12441Y-327600D02*
D03*
X14441Y-331600D02*
D03*
X12441Y-343600D02*
D03*
Y-351600D02*
D03*
X10441Y-139600D02*
D03*
Y-163600D02*
D03*
Y-171600D02*
D03*
X8441Y-191600D02*
D03*
X10441Y-195600D02*
D03*
Y-203600D02*
D03*
Y-227600D02*
D03*
Y-243600D02*
D03*
X8441Y-247600D02*
D03*
X10441Y-251600D02*
D03*
Y-259600D02*
D03*
Y-267600D02*
D03*
Y-275600D02*
D03*
X8441Y-279600D02*
D03*
X10441Y-299600D02*
D03*
Y-323600D02*
D03*
Y-331600D02*
D03*
X8441Y-351600D02*
D03*
X6441Y-139600D02*
D03*
X4441Y-191600D02*
D03*
X6441Y-243600D02*
D03*
X4441Y-351600D02*
D03*
X2441Y-243600D02*
D03*
X441Y-351600D02*
D03*
X-3559Y-191600D02*
D03*
X-1559Y-243600D02*
D03*
X-3559Y-351600D02*
D03*
X-5559Y-139600D02*
D03*
X-7559Y-143600D02*
D03*
Y-167600D02*
D03*
Y-191600D02*
D03*
Y-199600D02*
D03*
Y-223600D02*
D03*
X-5559Y-227600D02*
D03*
Y-243600D02*
D03*
X-7559Y-247600D02*
D03*
Y-279600D02*
D03*
X-5559Y-299600D02*
D03*
X-7559Y-303600D02*
D03*
Y-327600D02*
D03*
Y-351600D02*
D03*
X-9559Y-139600D02*
D03*
Y-171600D02*
D03*
X-11559Y-191600D02*
D03*
X-9559Y-195600D02*
D03*
Y-227600D02*
D03*
Y-243600D02*
D03*
X-11559Y-247600D02*
D03*
X-9559Y-251600D02*
D03*
Y-275600D02*
D03*
X-11559Y-279600D02*
D03*
X-9559Y-299600D02*
D03*
Y-331600D02*
D03*
X-11559Y-351600D02*
D03*
X-13559Y-139600D02*
D03*
X-15559Y-191600D02*
D03*
X-13559Y-243600D02*
D03*
X-15559Y-351600D02*
D03*
X-19559Y-263600D02*
D03*
Y-351600D02*
D03*
X-23559Y-159600D02*
D03*
Y-191600D02*
D03*
X-21559Y-211600D02*
D03*
X-23559Y-263600D02*
D03*
X-21559Y-315600D02*
D03*
X-23559Y-351600D02*
D03*
X-25559Y-139600D02*
D03*
Y-155600D02*
D03*
Y-211600D02*
D03*
Y-259600D02*
D03*
Y-267600D02*
D03*
Y-299600D02*
D03*
Y-315600D02*
D03*
X234252Y-133742D02*
D03*
X263779Y-106151D02*
D03*
X71850Y-147638D02*
D03*
X75787Y-131890D02*
D03*
X623000Y-37402D02*
D03*
X610236Y-8858D02*
D03*
X609252Y-26575D02*
D03*
X98425Y-102362D02*
D03*
X89567D02*
D03*
X85630Y-313976D02*
D03*
X86614Y-258858D02*
D03*
X81693Y-205709D02*
D03*
X63976Y-227362D02*
D03*
X68898Y-285433D02*
D03*
X67913Y-340551D02*
D03*
X68573Y-179321D02*
D03*
X44291Y-252953D02*
D03*
Y-272638D02*
D03*
Y-326772D02*
D03*
Y-307087D02*
D03*
X26575Y-291339D02*
D03*
X31496Y-189961D02*
D03*
X44291Y-147638D02*
D03*
Y-167323D02*
D03*
Y-200787D02*
D03*
Y-220472D02*
D03*
X103409Y-141732D02*
D03*
X103347Y-110236D02*
D03*
X119095Y-126047D02*
D03*
X518701Y-104214D02*
D03*
X519587Y-134596D02*
D03*
X528543Y-104214D02*
D03*
X114173Y-83088D02*
D03*
X441929Y-122883D02*
D03*
X129921Y-79576D02*
D03*
X163071Y-390730D02*
D03*
X99410Y-50049D02*
D03*
X259285Y-390247D02*
D03*
X267204Y-390009D02*
D03*
X216162Y-390947D02*
D03*
X235144Y-390416D02*
D03*
X251456Y-390009D02*
D03*
X226063Y-390722D02*
D03*
X281201Y-390009D02*
D03*
X174941Y-390600D02*
D03*
X202441D02*
D03*
D251*
X348211Y-89891D02*
D03*
X357798Y-89963D02*
D03*
D253*
X99016Y-121653D02*
D03*
X103347D02*
D03*
X107677D02*
D03*
X99016Y-125984D02*
D03*
X103347D02*
D03*
X107677D02*
D03*
X99016Y-130315D02*
D03*
X103347D02*
D03*
X107677D02*
D03*
M02*
